FILE_TYPE = MACRO_DRAWING;
SET COLOR_WIRE YELLOW;
SET COLOR_PROP MONO;
SET COLOR_DOT WHITE;
SET COLOR_ARC YELLOW;
SET COLOR_BODY GREEN;
SET COLOR_NOTE MONO;
SET PROP_DISPLAY VALUE;
SET PAGE_NUMBER P103;
FORCEADD RES..1
(300 1250);
FORCEPROP 1 LAST VALUE 27.4
J 2
(225 1200);
DISPLAY 0.617021 (225 1200);
PAINT SKYBLUE (225 1200);
FORCEPROP 1 LASTPIN (200 1250) $PN 1
J 0
(212 1262);
DISPLAY 0.617021 (212 1262);
PAINT ORANGE (212 1262);
FORCEPROP 1 LAST WATTAGE 1/16W
J 2
(275 1150);
DISPLAY 0.617021 (275 1150);
PAINT SKYBLUE (275 1150);
FORCEPROP 1 LAST LOCATION R4D25
J 0
(250 1300);
DISPLAY 0.617021 (250 1300);
PAINT AQUA (250 1300);
FORCEPROP 1 LAST TOLERANCE 1%
J 0
(300 1150);
DISPLAY 0.617021 (300 1150);
PAINT SKYBLUE (300 1150);
FORCEPROP 1 LAST PACK_TYPE 0402
J 0
(375 1150);
DISPLAY 0.617021 (375 1150);
PAINT SKYBLUE (375 1150);
FORCEPROP 1 LAST MATERIAL CHIP
J 0
(350 1200);
DISPLAY 0.617021 (350 1200);
PAINT SKYBLUE (350 1200);
FORCEPROP 1 LASTPIN (400 1250) $PN 2
J 0
(362 1262);
DISPLAY 0.617021 (362 1262);
PAINT ORANGE (362 1262);
FORCEPROP 1 LAST PART_NUMBER G21796-182
J 0
(425 1250);
DISPLAY 0.617021 (425 1250);
PAINT BLUE (425 1250);
FORCEPROP 0 LAST ROOM DB1200Z
J 0
(250 1400);
DISPLAY 1.021277 (250 1400);
PAINT ORANGE (250 1400);
DISPLAY INVISIBLE (250 1400);
FORCEPROP 1 LAST PATH I1
J 0
(250 1400);
DISPLAY 0.978723 (250 1400);
PAINT WHITE (250 1400);
DISPLAY INVISIBLE (250 1400);
FORCEPROP 2 LAST CDS_LOCATION R4D25
J 0
(250 1300);
DISPLAY 0.617021 (250 1300);
PAINT AQUA (250 1300);
DISPLAY INVISIBLE (250 1300);
FORCEPROP 2 LAST SEC 1
J 0
(250 1450);
DISPLAY 0.680851 (250 1450);
PAINT MONO (250 1450);
DISPLAY INVISIBLE (250 1450);
FORCEPROP 2 LAST SEC_TYPE 0402
J 0
(250 1450);
DISPLAY 1.021277 (250 1450);
PAINT ORANGE (250 1450);
DISPLAY INVISIBLE (250 1450);
FORCEPROP 2 LAST CDS_LIB mstr_discrete
J 0
(300 1250);
PAINT ORANGE (300 1250);
DISPLAY INVISIBLE (300 1250);
FORCEPROP 0 LAST BOM_COST SYS_CLOCK
J 0
(250 1500);
DISPLAY 1.021277 (250 1500);
PAINT ORANGE (250 1500);
DISPLAY INVISIBLE (250 1500);
FORCEADD OFFPAGE..1
(-4900 4900);
FORCEPROP 2 LAST $XR0 102 
J 0
(-5152 4900);
DISPLAY 0.638298 (-5152 4900);
PAINT MONO (-5152 4900);
FORCEPROP 2 LAST CDS_LIB mstr_standard
J 0
(-4900 4900);
PAINT ORANGE (-4900 4900);
DISPLAY INVISIBLE (-4900 4900);
FORCEPROP 2 LAST PATH I10
J 0
(-4850 4975);
DISPLAY 1.021277 (-4850 4975);
PAINT ORANGE (-4850 4975);
DISPLAY INVISIBLE (-4850 4975);
FORCEPROP 1 LAST OFFPAGE TRUE
J 0
(-4575 4775);
DISPLAY 0.872340 (-4575 4775);
PAINT GREEN (-4575 4775);
DISPLAY INVISIBLE (-4575 4775);
FORCEPROP 1 LAST COMMENT_BODY TRUE
J 0
(-4775 4800);
DISPLAY 0.872340 (-4775 4800);
PAINT GREEN (-4775 4800);
DISPLAY INVISIBLE (-4775 4800);
FORCEADD OFFPAGE..1
(-675 3200);
FORCEPROP 2 LAST $XR0 102 
J 0
(-927 3200);
DISPLAY 0.638298 (-927 3200);
PAINT MONO (-927 3200);
FORCEPROP 2 LAST PATH I100
J 0
(-625 3275);
DISPLAY 1.021277 (-625 3275);
PAINT ORANGE (-625 3275);
DISPLAY INVISIBLE (-625 3275);
FORCEPROP 2 LAST CDS_LIB mstr_standard
J 0
(-675 3200);
PAINT ORANGE (-675 3200);
DISPLAY INVISIBLE (-675 3200);
FORCEPROP 1 LAST OFFPAGE TRUE
J 0
(-350 3075);
DISPLAY 0.872340 (-350 3075);
PAINT GREEN (-350 3075);
DISPLAY INVISIBLE (-350 3075);
FORCEPROP 1 LAST COMMENT_BODY TRUE
J 0
(-550 3100);
DISPLAY 0.872340 (-550 3100);
PAINT GREEN (-550 3100);
DISPLAY INVISIBLE (-550 3100);
FORCEADD OFFPAGE..2
(1950 2875);
FORCEPROP 2 LAST $XR0 21 
J 0
(2139 2875);
DISPLAY 0.638298 (2139 2875);
PAINT MONO (2139 2875);
FORCEPROP 2 LAST CDS_LIB mstr_standard
J 0
(1950 2875);
PAINT ORANGE (1950 2875);
DISPLAY INVISIBLE (1950 2875);
FORCEPROP 2 LAST PATH I102
J 0
(2125 2950);
DISPLAY 1.021277 (2125 2950);
PAINT ORANGE (2125 2950);
DISPLAY INVISIBLE (2125 2950);
FORCEPROP 1 LAST OFFPAGE TRUE
J 0
(2275 2750);
DISPLAY 0.872340 (2275 2750);
PAINT GREEN (2275 2750);
DISPLAY INVISIBLE (2275 2750);
FORCEPROP 1 LAST COMMENT_BODY TRUE
J 0
(1905 2780);
DISPLAY 0.872340 (1905 2780);
PAINT GREEN (1905 2780);
DISPLAY INVISIBLE (1905 2780);
FORCEADD RES..1
(300 2875);
FORCEPROP 1 LASTPIN (200 2875) $PN 1
J 0
(212 2887);
DISPLAY 0.617021 (212 2887);
PAINT ORANGE (212 2887);
FORCEPROP 1 LAST VALUE 27.4
J 2
(225 2825);
DISPLAY 0.617021 (225 2825);
PAINT SKYBLUE (225 2825);
FORCEPROP 1 LAST WATTAGE 1/16W
J 2
(275 2775);
DISPLAY 0.617021 (275 2775);
PAINT SKYBLUE (275 2775);
FORCEPROP 1 LAST LOCATION R4D17
J 0
(250 2925);
DISPLAY 0.617021 (250 2925);
PAINT AQUA (250 2925);
FORCEPROP 1 LAST TOLERANCE 1%
J 0
(300 2775);
DISPLAY 0.617021 (300 2775);
PAINT SKYBLUE (300 2775);
FORCEPROP 1 LAST PACK_TYPE 0402
J 0
(375 2775);
DISPLAY 0.617021 (375 2775);
PAINT SKYBLUE (375 2775);
FORCEPROP 1 LAST MATERIAL CHIP
J 0
(350 2825);
DISPLAY 0.617021 (350 2825);
PAINT SKYBLUE (350 2825);
FORCEPROP 1 LASTPIN (400 2875) $PN 2
J 0
(362 2887);
DISPLAY 0.617021 (362 2887);
PAINT ORANGE (362 2887);
FORCEPROP 1 LAST PART_NUMBER G21796-182
J 0
(425 2875);
DISPLAY 0.617021 (425 2875);
PAINT BLUE (425 2875);
FORCEPROP 0 LAST ROOM DB1200Z
J 0
(250 3025);
DISPLAY 1.021277 (250 3025);
PAINT ORANGE (250 3025);
DISPLAY INVISIBLE (250 3025);
FORCEPROP 1 LAST PATH I104
J 0
(250 3025);
DISPLAY 0.978723 (250 3025);
PAINT WHITE (250 3025);
DISPLAY INVISIBLE (250 3025);
FORCEPROP 2 LAST CDS_LOCATION R4D17
J 0
(250 2925);
DISPLAY 0.617021 (250 2925);
PAINT AQUA (250 2925);
DISPLAY INVISIBLE (250 2925);
FORCEPROP 2 LAST CDS_LIB mstr_discrete
J 0
(300 2875);
PAINT ORANGE (300 2875);
DISPLAY INVISIBLE (300 2875);
FORCEPROP 0 LAST BOM_COST SYS_CLOCK
J 0
(250 3125);
DISPLAY 1.021277 (250 3125);
PAINT ORANGE (250 3125);
DISPLAY INVISIBLE (250 3125);
FORCEPROP 2 LAST SEC_TYPE 0402
J 0
(250 3075);
DISPLAY 1.021277 (250 3075);
PAINT ORANGE (250 3075);
DISPLAY INVISIBLE (250 3075);
FORCEPROP 2 LAST SEC 1
J 0
(250 3075);
DISPLAY 0.680851 (250 3075);
PAINT MONO (250 3075);
DISPLAY INVISIBLE (250 3075);
FORCEADD OFFPAGE..1
(-675 2875);
FORCEPROP 2 LAST $XR0 102 
J 0
(-927 2875);
DISPLAY 0.638298 (-927 2875);
PAINT MONO (-927 2875);
FORCEPROP 2 LAST PATH I105
J 0
(-625 2950);
DISPLAY 1.021277 (-625 2950);
PAINT ORANGE (-625 2950);
DISPLAY INVISIBLE (-625 2950);
FORCEPROP 2 LAST CDS_LIB mstr_standard
J 0
(-675 2875);
PAINT ORANGE (-675 2875);
DISPLAY INVISIBLE (-675 2875);
FORCEPROP 1 LAST OFFPAGE TRUE
J 0
(-350 2750);
DISPLAY 0.872340 (-350 2750);
PAINT GREEN (-350 2750);
DISPLAY INVISIBLE (-350 2750);
FORCEPROP 1 LAST COMMENT_BODY TRUE
J 0
(-550 2775);
DISPLAY 0.872340 (-550 2775);
PAINT GREEN (-550 2775);
DISPLAY INVISIBLE (-550 2775);
FORCEADD OFFPAGE..2
(1950 2550);
FORCEPROP 2 LAST $XR0 21 
J 0
(2139 2550);
DISPLAY 0.638298 (2139 2550);
PAINT MONO (2139 2550);
FORCEPROP 2 LAST CDS_LIB mstr_standard
J 0
(1950 2550);
PAINT ORANGE (1950 2550);
DISPLAY INVISIBLE (1950 2550);
FORCEPROP 2 LAST PATH I108
J 0
(2125 2625);
DISPLAY 1.021277 (2125 2625);
PAINT ORANGE (2125 2625);
DISPLAY INVISIBLE (2125 2625);
FORCEPROP 1 LAST OFFPAGE TRUE
J 0
(2275 2425);
DISPLAY 0.872340 (2275 2425);
PAINT GREEN (2275 2425);
DISPLAY INVISIBLE (2275 2425);
FORCEPROP 1 LAST COMMENT_BODY TRUE
J 0
(1905 2455);
DISPLAY 0.872340 (1905 2455);
PAINT GREEN (1905 2455);
DISPLAY INVISIBLE (1905 2455);
FORCEADD RES..1
(300 2550);
FORCEPROP 1 LAST VALUE 27.4
J 2
(225 2500);
DISPLAY 0.617021 (225 2500);
PAINT SKYBLUE (225 2500);
FORCEPROP 1 LAST WATTAGE 1/16W
J 2
(275 2450);
DISPLAY 0.617021 (275 2450);
PAINT SKYBLUE (275 2450);
FORCEPROP 1 LAST MATERIAL CHIP
J 0
(350 2500);
DISPLAY 0.617021 (350 2500);
PAINT SKYBLUE (350 2500);
FORCEPROP 1 LAST PACK_TYPE 0402
J 0
(375 2450);
DISPLAY 0.617021 (375 2450);
PAINT SKYBLUE (375 2450);
FORCEPROP 1 LAST TOLERANCE 1%
J 0
(300 2450);
DISPLAY 0.617021 (300 2450);
PAINT SKYBLUE (300 2450);
FORCEPROP 1 LASTPIN (200 2550) $PN 1
J 0
(212 2562);
DISPLAY 0.617021 (212 2562);
PAINT ORANGE (212 2562);
FORCEPROP 1 LAST LOCATION R4D14
J 0
(250 2575);
DISPLAY 0.617021 (250 2575);
PAINT AQUA (250 2575);
FORCEPROP 1 LASTPIN (400 2550) $PN 2
J 0
(362 2562);
DISPLAY 0.617021 (362 2562);
PAINT ORANGE (362 2562);
FORCEPROP 1 LAST PART_NUMBER G21796-182
J 0
(425 2550);
DISPLAY 0.617021 (425 2550);
PAINT BLUE (425 2550);
FORCEPROP 2 LAST CDS_LIB mstr_discrete
J 0
(300 2550);
PAINT ORANGE (300 2550);
DISPLAY INVISIBLE (300 2550);
FORCEPROP 1 LAST PATH I109
J 0
(250 2700);
DISPLAY 0.978723 (250 2700);
PAINT WHITE (250 2700);
DISPLAY INVISIBLE (250 2700);
FORCEPROP 2 LAST SEC_TYPE 0402
J 0
(250 2750);
DISPLAY 1.021277 (250 2750);
PAINT ORANGE (250 2750);
DISPLAY INVISIBLE (250 2750);
FORCEPROP 0 LAST ROOM DB1200Z
J 0
(250 2675);
DISPLAY 1.021277 (250 2675);
PAINT ORANGE (250 2675);
DISPLAY INVISIBLE (250 2675);
FORCEPROP 0 LAST BOM_COST SYS_CLOCK
J 0
(250 2775);
DISPLAY 1.021277 (250 2775);
PAINT ORANGE (250 2775);
DISPLAY INVISIBLE (250 2775);
FORCEPROP 2 LAST SEC 1
J 0
(250 2750);
DISPLAY 0.680851 (250 2750);
PAINT MONO (250 2750);
DISPLAY INVISIBLE (250 2750);
FORCEPROP 2 LAST CDS_LOCATION R4D14
J 0
(250 2575);
DISPLAY 0.617021 (250 2575);
PAINT AQUA (250 2575);
DISPLAY INVISIBLE (250 2575);
FORCEADD OFFPAGE..2
(-2225 4525);
FORCEPROP 2 LAST $XR0 70 
J 0
(-2036 4525);
DISPLAY 0.638298 (-2036 4525);
PAINT MONO (-2036 4525);
FORCEPROP 2 LAST CDS_LIB mstr_standard
J 0
(-2225 4525);
PAINT ORANGE (-2225 4525);
DISPLAY INVISIBLE (-2225 4525);
FORCEPROP 2 LAST PATH I11
J 0
(-2050 4600);
DISPLAY 1.021277 (-2050 4600);
PAINT ORANGE (-2050 4600);
DISPLAY INVISIBLE (-2050 4600);
FORCEPROP 1 LAST OFFPAGE TRUE
J 0
(-1900 4400);
DISPLAY 0.872340 (-1900 4400);
PAINT GREEN (-1900 4400);
DISPLAY INVISIBLE (-1900 4400);
FORCEPROP 1 LAST COMMENT_BODY TRUE
J 0
(-2270 4430);
DISPLAY 0.872340 (-2270 4430);
PAINT GREEN (-2270 4430);
DISPLAY INVISIBLE (-2270 4430);
FORCEADD OFFPAGE..1
(-675 2550);
FORCEPROP 2 LAST $XR0 102 
J 0
(-927 2550);
DISPLAY 0.638298 (-927 2550);
PAINT MONO (-927 2550);
FORCEPROP 2 LAST CDS_LIB mstr_standard
J 0
(-675 2550);
PAINT ORANGE (-675 2550);
DISPLAY INVISIBLE (-675 2550);
FORCEPROP 2 LAST PATH I110
J 0
(-625 2625);
DISPLAY 1.021277 (-625 2625);
PAINT ORANGE (-625 2625);
DISPLAY INVISIBLE (-625 2625);
FORCEPROP 1 LAST OFFPAGE TRUE
J 0
(-350 2425);
DISPLAY 0.872340 (-350 2425);
PAINT GREEN (-350 2425);
DISPLAY INVISIBLE (-350 2425);
FORCEPROP 1 LAST COMMENT_BODY TRUE
J 0
(-550 2450);
DISPLAY 0.872340 (-550 2450);
PAINT GREEN (-550 2450);
DISPLAY INVISIBLE (-550 2450);
FORCEADD OFFPAGE..2
(1950 2225);
FORCEPROP 2 LAST $XR0 21 
J 0
(2139 2225);
DISPLAY 0.638298 (2139 2225);
PAINT MONO (2139 2225);
FORCEPROP 2 LAST CDS_LIB mstr_standard
J 0
(1950 2225);
PAINT ORANGE (1950 2225);
DISPLAY INVISIBLE (1950 2225);
FORCEPROP 2 LAST PATH I113
J 0
(2125 2300);
DISPLAY 1.021277 (2125 2300);
PAINT ORANGE (2125 2300);
DISPLAY INVISIBLE (2125 2300);
FORCEPROP 1 LAST OFFPAGE TRUE
J 0
(2275 2100);
DISPLAY 0.872340 (2275 2100);
PAINT GREEN (2275 2100);
DISPLAY INVISIBLE (2275 2100);
FORCEPROP 1 LAST COMMENT_BODY TRUE
J 0
(1905 2130);
DISPLAY 0.872340 (1905 2130);
PAINT GREEN (1905 2130);
DISPLAY INVISIBLE (1905 2130);
FORCEADD RES..1
(300 2225);
FORCEPROP 1 LAST VALUE 27.4
J 2
(225 2175);
DISPLAY 0.617021 (225 2175);
PAINT SKYBLUE (225 2175);
FORCEPROP 1 LASTPIN (200 2225) $PN 1
J 0
(212 2237);
DISPLAY 0.617021 (212 2237);
PAINT ORANGE (212 2237);
FORCEPROP 1 LAST WATTAGE 1/16W
J 2
(275 2125);
DISPLAY 0.617021 (275 2125);
PAINT SKYBLUE (275 2125);
FORCEPROP 1 LAST LOCATION R4D22
J 0
(250 2275);
DISPLAY 0.617021 (250 2275);
PAINT AQUA (250 2275);
FORCEPROP 1 LAST MATERIAL CHIP
J 0
(350 2175);
DISPLAY 0.617021 (350 2175);
PAINT SKYBLUE (350 2175);
FORCEPROP 1 LAST PACK_TYPE 0402
J 0
(375 2125);
DISPLAY 0.617021 (375 2125);
PAINT SKYBLUE (375 2125);
FORCEPROP 1 LAST TOLERANCE 1%
J 0
(300 2125);
DISPLAY 0.617021 (300 2125);
PAINT SKYBLUE (300 2125);
FORCEPROP 1 LASTPIN (400 2225) $PN 2
J 0
(362 2237);
DISPLAY 0.617021 (362 2237);
PAINT ORANGE (362 2237);
FORCEPROP 1 LAST PART_NUMBER G21796-182
J 0
(425 2225);
DISPLAY 0.617021 (425 2225);
PAINT BLUE (425 2225);
FORCEPROP 2 LAST CDS_LOCATION R4D22
J 0
(250 2275);
DISPLAY 0.617021 (250 2275);
PAINT AQUA (250 2275);
DISPLAY INVISIBLE (250 2275);
FORCEPROP 2 LAST SEC_TYPE 0402
J 0
(250 2425);
DISPLAY 1.021277 (250 2425);
PAINT ORANGE (250 2425);
DISPLAY INVISIBLE (250 2425);
FORCEPROP 0 LAST BOM_COST SYS_CLOCK
J 0
(250 2475);
DISPLAY 1.021277 (250 2475);
PAINT ORANGE (250 2475);
DISPLAY INVISIBLE (250 2475);
FORCEPROP 2 LAST SEC 1
J 0
(250 2425);
DISPLAY 0.680851 (250 2425);
PAINT MONO (250 2425);
DISPLAY INVISIBLE (250 2425);
FORCEPROP 1 LAST PATH I114
J 0
(250 2375);
DISPLAY 0.978723 (250 2375);
PAINT WHITE (250 2375);
DISPLAY INVISIBLE (250 2375);
FORCEPROP 0 LAST ROOM DB1200Z
J 0
(250 2375);
DISPLAY 1.021277 (250 2375);
PAINT ORANGE (250 2375);
DISPLAY INVISIBLE (250 2375);
FORCEPROP 2 LAST CDS_LIB mstr_discrete
J 0
(300 2225);
PAINT ORANGE (300 2225);
DISPLAY INVISIBLE (300 2225);
FORCEADD OFFPAGE..1
(-675 2225);
FORCEPROP 2 LAST $XR0 102 
J 0
(-927 2225);
DISPLAY 0.638298 (-927 2225);
PAINT MONO (-927 2225);
FORCEPROP 2 LAST CDS_LIB mstr_standard
J 0
(-675 2225);
PAINT ORANGE (-675 2225);
DISPLAY INVISIBLE (-675 2225);
FORCEPROP 2 LAST PATH I115
J 0
(-625 2300);
DISPLAY 1.021277 (-625 2300);
PAINT ORANGE (-625 2300);
DISPLAY INVISIBLE (-625 2300);
FORCEPROP 1 LAST OFFPAGE TRUE
J 0
(-350 2100);
DISPLAY 0.872340 (-350 2100);
PAINT GREEN (-350 2100);
DISPLAY INVISIBLE (-350 2100);
FORCEPROP 1 LAST COMMENT_BODY TRUE
J 0
(-550 2125);
DISPLAY 0.872340 (-550 2125);
PAINT GREEN (-550 2125);
DISPLAY INVISIBLE (-550 2125);
FORCEADD OFFPAGE..2
(1950 1900);
FORCEPROP 2 LAST $XR0 21 
J 0
(2139 1900);
DISPLAY 0.638298 (2139 1900);
PAINT MONO (2139 1900);
FORCEPROP 2 LAST CDS_LIB mstr_standard
J 0
(1950 1900);
PAINT ORANGE (1950 1900);
DISPLAY INVISIBLE (1950 1900);
FORCEPROP 2 LAST PATH I118
J 0
(2125 1975);
DISPLAY 1.021277 (2125 1975);
PAINT ORANGE (2125 1975);
DISPLAY INVISIBLE (2125 1975);
FORCEPROP 1 LAST OFFPAGE TRUE
J 0
(2275 1775);
DISPLAY 0.872340 (2275 1775);
PAINT GREEN (2275 1775);
DISPLAY INVISIBLE (2275 1775);
FORCEPROP 1 LAST COMMENT_BODY TRUE
J 0
(1905 1805);
DISPLAY 0.872340 (1905 1805);
PAINT GREEN (1905 1805);
DISPLAY INVISIBLE (1905 1805);
FORCEADD RES..1
(300 1900);
FORCEPROP 1 LASTPIN (200 1900) $PN 1
J 0
(212 1912);
DISPLAY 0.617021 (212 1912);
PAINT ORANGE (212 1912);
FORCEPROP 1 LAST VALUE 27.4
J 2
(225 1850);
DISPLAY 0.617021 (225 1850);
PAINT SKYBLUE (225 1850);
FORCEPROP 1 LAST WATTAGE 1/16W
J 2
(275 1800);
DISPLAY 0.617021 (275 1800);
PAINT SKYBLUE (275 1800);
FORCEPROP 1 LAST LOCATION R4D20
J 0
(250 1950);
DISPLAY 0.617021 (250 1950);
PAINT AQUA (250 1950);
FORCEPROP 1 LASTPIN (400 1900) $PN 2
J 0
(362 1912);
DISPLAY 0.617021 (362 1912);
PAINT ORANGE (362 1912);
FORCEPROP 1 LAST MATERIAL CHIP
J 0
(350 1850);
DISPLAY 0.617021 (350 1850);
PAINT SKYBLUE (350 1850);
FORCEPROP 1 LAST PACK_TYPE 0402
J 0
(375 1800);
DISPLAY 0.617021 (375 1800);
PAINT SKYBLUE (375 1800);
FORCEPROP 1 LAST TOLERANCE 1%
J 0
(300 1800);
DISPLAY 0.617021 (300 1800);
PAINT SKYBLUE (300 1800);
FORCEPROP 1 LAST PART_NUMBER G21796-182
J 0
(425 1900);
DISPLAY 0.617021 (425 1900);
PAINT BLUE (425 1900);
FORCEPROP 2 LAST CDS_LOCATION R4D20
J 0
(250 1950);
DISPLAY 0.617021 (250 1950);
PAINT AQUA (250 1950);
DISPLAY INVISIBLE (250 1950);
FORCEPROP 2 LAST CDS_LIB mstr_discrete
J 0
(300 1900);
PAINT ORANGE (300 1900);
DISPLAY INVISIBLE (300 1900);
FORCEPROP 2 LAST SEC_TYPE 0402
J 0
(250 2100);
DISPLAY 1.021277 (250 2100);
PAINT ORANGE (250 2100);
DISPLAY INVISIBLE (250 2100);
FORCEPROP 0 LAST BOM_COST SYS_CLOCK
J 0
(250 2150);
DISPLAY 1.021277 (250 2150);
PAINT ORANGE (250 2150);
DISPLAY INVISIBLE (250 2150);
FORCEPROP 2 LAST SEC 1
J 0
(250 2100);
DISPLAY 0.680851 (250 2100);
PAINT MONO (250 2100);
DISPLAY INVISIBLE (250 2100);
FORCEPROP 1 LAST PATH I119
J 0
(250 2050);
DISPLAY 0.978723 (250 2050);
PAINT WHITE (250 2050);
DISPLAY INVISIBLE (250 2050);
FORCEPROP 0 LAST ROOM DB1200Z
J 0
(250 2050);
DISPLAY 1.021277 (250 2050);
PAINT ORANGE (250 2050);
DISPLAY INVISIBLE (250 2050);
FORCEADD OFFPAGE..1
(-675 1900);
FORCEPROP 2 LAST $XR0 102 
J 0
(-927 1900);
DISPLAY 0.638298 (-927 1900);
PAINT MONO (-927 1900);
FORCEPROP 2 LAST PATH I120
J 0
(-625 1975);
DISPLAY 1.021277 (-625 1975);
PAINT ORANGE (-625 1975);
DISPLAY INVISIBLE (-625 1975);
FORCEPROP 2 LAST CDS_LIB mstr_standard
J 0
(-675 1900);
PAINT ORANGE (-675 1900);
DISPLAY INVISIBLE (-675 1900);
FORCEPROP 1 LAST OFFPAGE TRUE
J 0
(-350 1775);
DISPLAY 0.872340 (-350 1775);
PAINT GREEN (-350 1775);
DISPLAY INVISIBLE (-350 1775);
FORCEPROP 1 LAST COMMENT_BODY TRUE
J 0
(-550 1800);
DISPLAY 0.872340 (-550 1800);
PAINT GREEN (-550 1800);
DISPLAY INVISIBLE (-550 1800);
FORCEADD RES..1
(-3325 4800);
FORCEPROP 1 LAST WATTAGE 1/16W
J 2
(-3350 4650);
DISPLAY 0.617021 (-3350 4650);
PAINT SKYBLUE (-3350 4650);
FORCEPROP 1 LAST VALUE 42.2
J 2
(-3350 4700);
DISPLAY 0.617021 (-3350 4700);
PAINT SKYBLUE (-3350 4700);
FORCEPROP 1 LASTPIN (-3425 4800) $PN 1
J 0
(-3413 4812);
DISPLAY 0.617021 (-3413 4812);
PAINT ORANGE (-3413 4812);
FORCEPROP 1 LAST PART_NUMBER G21796-259
J 0
(-3375 4900);
DISPLAY 0.617021 (-3375 4900);
PAINT BLUE (-3375 4900);
FORCEPROP 1 LAST LOCATION R7P9
J 0
(-3375 4850);
DISPLAY 0.617021 (-3375 4850);
PAINT AQUA (-3375 4850);
FORCEPROP 1 LAST TOLERANCE 1.0%
J 0
(-3325 4700);
DISPLAY 0.617021 (-3325 4700);
PAINT SKYBLUE (-3325 4700);
FORCEPROP 1 LASTPIN (-3225 4800) $PN 2
J 0
(-3263 4812);
DISPLAY 0.617021 (-3263 4812);
PAINT ORANGE (-3263 4812);
FORCEPROP 1 LAST MATERIAL EMPTY
J 0
(-3325 4650);
DISPLAY 0.617021 (-3325 4650);
PAINT RED (-3325 4650);
FORCEPROP 1 LAST PACK_TYPE 0402
J 0
(-3075 4650);
DISPLAY 0.617021 (-3075 4650);
PAINT SKYBLUE (-3075 4650);
FORCEPROP 2 LAST CDS_LOCATION R7P9
J 0
(-3375 4850);
DISPLAY 0.617021 (-3375 4850);
PAINT AQUA (-3375 4850);
DISPLAY INVISIBLE (-3375 4850);
FORCEPROP 0 LAST ROOM DB1200Z
J 0
(-3375 5000);
DISPLAY 1.021277 (-3375 5000);
PAINT ORANGE (-3375 5000);
DISPLAY INVISIBLE (-3375 5000);
FORCEPROP 1 LAST PATH I121
J 0
(-3375 4950);
DISPLAY 0.978723 (-3375 4950);
PAINT WHITE (-3375 4950);
DISPLAY INVISIBLE (-3375 4950);
FORCEPROP 2 LAST SEC 1
J 0
(-3375 5000);
DISPLAY 0.680851 (-3375 5000);
PAINT MONO (-3375 5000);
DISPLAY INVISIBLE (-3375 5000);
FORCEPROP 2 LAST SEC_TYPE 0402
J 0
(-3375 5000);
DISPLAY 1.021277 (-3375 5000);
PAINT ORANGE (-3375 5000);
DISPLAY INVISIBLE (-3375 5000);
FORCEPROP 2 LAST CDS_LIB mstr_discrete
J 0
(-3325 4800);
PAINT MONO (-3325 4800);
DISPLAY INVISIBLE (-3325 4800);
FORCEPROP 0 LAST BOM_COST SYS_CLOCK
J 0
(-3375 5100);
DISPLAY 1.021277 (-3375 5100);
PAINT ORANGE (-3375 5100);
DISPLAY INVISIBLE (-3375 5100);
FORCEADD RES..1
(-3300 4425);
FORCEPROP 1 LASTPIN (-3400 4425) $PN 1
J 0
(-3388 4437);
DISPLAY 0.617021 (-3388 4437);
PAINT ORANGE (-3388 4437);
FORCEPROP 1 LAST WATTAGE 1/16W
J 2
(-3325 4275);
DISPLAY 0.617021 (-3325 4275);
PAINT SKYBLUE (-3325 4275);
FORCEPROP 1 LAST VALUE 42.2
J 2
(-3325 4325);
DISPLAY 0.617021 (-3325 4325);
PAINT SKYBLUE (-3325 4325);
FORCEPROP 1 LAST LOCATION R7P12
J 0
(-3350 4475);
DISPLAY 0.617021 (-3350 4475);
PAINT AQUA (-3350 4475);
FORCEPROP 1 LAST TOLERANCE 1.0%
J 0
(-3300 4325);
DISPLAY 0.617021 (-3300 4325);
PAINT SKYBLUE (-3300 4325);
FORCEPROP 1 LAST MATERIAL EMPTY
J 0
(-3300 4275);
DISPLAY 0.617021 (-3300 4275);
PAINT RED (-3300 4275);
FORCEPROP 1 LASTPIN (-3200 4425) $PN 2
J 0
(-3238 4437);
DISPLAY 0.617021 (-3238 4437);
PAINT ORANGE (-3238 4437);
FORCEPROP 1 LAST PART_NUMBER G21796-259
J 0
(-3350 4525);
DISPLAY 0.617021 (-3350 4525);
PAINT BLUE (-3350 4525);
FORCEPROP 1 LAST PACK_TYPE 0402
J 0
(-3050 4275);
DISPLAY 0.617021 (-3050 4275);
PAINT SKYBLUE (-3050 4275);
FORCEPROP 2 LAST CDS_LOCATION R7P12
J 0
(-3350 4475);
DISPLAY 0.617021 (-3350 4475);
PAINT AQUA (-3350 4475);
DISPLAY INVISIBLE (-3350 4475);
FORCEPROP 2 LAST CDS_LIB mstr_discrete
J 0
(-3300 4425);
PAINT MONO (-3300 4425);
DISPLAY INVISIBLE (-3300 4425);
FORCEPROP 1 LAST PATH I123
J 0
(-3350 4575);
DISPLAY 0.978723 (-3350 4575);
PAINT WHITE (-3350 4575);
DISPLAY INVISIBLE (-3350 4575);
FORCEPROP 0 LAST ROOM DB1200Z
J 0
(-3350 4625);
DISPLAY 1.021277 (-3350 4625);
PAINT ORANGE (-3350 4625);
DISPLAY INVISIBLE (-3350 4625);
FORCEPROP 2 LAST SEC 1
J 0
(-3350 4625);
DISPLAY 0.680851 (-3350 4625);
PAINT MONO (-3350 4625);
DISPLAY INVISIBLE (-3350 4625);
FORCEPROP 2 LAST SEC_TYPE 0402
J 0
(-3350 4625);
DISPLAY 1.021277 (-3350 4625);
PAINT ORANGE (-3350 4625);
DISPLAY INVISIBLE (-3350 4625);
FORCEPROP 0 LAST BOM_COST SYS_CLOCK
J 0
(-3350 4725);
DISPLAY 1.021277 (-3350 4725);
PAINT ORANGE (-3350 4725);
DISPLAY INVISIBLE (-3350 4725);
FORCEADD RES..1
(-3325 4075);
FORCEPROP 1 LAST WATTAGE 1/16W
J 2
(-3350 3925);
DISPLAY 0.617021 (-3350 3925);
PAINT SKYBLUE (-3350 3925);
FORCEPROP 1 LAST VALUE 42.2
J 2
(-3350 3975);
DISPLAY 0.617021 (-3350 3975);
PAINT SKYBLUE (-3350 3975);
FORCEPROP 1 LAST TOLERANCE 1.0%
J 0
(-3325 3975);
DISPLAY 0.617021 (-3325 3975);
PAINT SKYBLUE (-3325 3975);
FORCEPROP 1 LAST MATERIAL EMPTY
J 0
(-3325 3925);
DISPLAY 0.617021 (-3325 3925);
PAINT RED (-3325 3925);
FORCEPROP 1 LAST PACK_TYPE 0402
J 0
(-3075 3925);
DISPLAY 0.617021 (-3075 3925);
PAINT SKYBLUE (-3075 3925);
FORCEPROP 1 LASTPIN (-3425 4075) $PN 1
J 0
(-3413 4087);
DISPLAY 0.617021 (-3413 4087);
PAINT ORANGE (-3413 4087);
FORCEPROP 1 LASTPIN (-3225 4075) $PN 2
J 0
(-3263 4087);
DISPLAY 0.617021 (-3263 4087);
PAINT ORANGE (-3263 4087);
FORCEPROP 1 LAST PART_NUMBER G21796-259
J 0
(-3175 4075);
DISPLAY 0.617021 (-3175 4075);
PAINT BLUE (-3175 4075);
FORCEPROP 1 LAST LOCATION R7P6
J 0
(-3375 4125);
DISPLAY 0.617021 (-3375 4125);
PAINT AQUA (-3375 4125);
FORCEPROP 2 LAST CDS_LIB mstr_discrete
J 0
(-3325 4075);
PAINT MONO (-3325 4075);
DISPLAY INVISIBLE (-3325 4075);
FORCEPROP 2 LAST SEC_TYPE 0402
J 0
(-3375 4275);
DISPLAY 1.021277 (-3375 4275);
PAINT ORANGE (-3375 4275);
DISPLAY INVISIBLE (-3375 4275);
FORCEPROP 2 LAST SEC 1
J 0
(-3375 4275);
DISPLAY 0.680851 (-3375 4275);
PAINT MONO (-3375 4275);
DISPLAY INVISIBLE (-3375 4275);
FORCEPROP 2 LAST CDS_LOCATION R7P6
J 0
(-3375 4125);
DISPLAY 0.617021 (-3375 4125);
PAINT AQUA (-3375 4125);
DISPLAY INVISIBLE (-3375 4125);
FORCEPROP 1 LAST PATH I125
J 0
(-3375 4225);
DISPLAY 0.978723 (-3375 4225);
PAINT WHITE (-3375 4225);
DISPLAY INVISIBLE (-3375 4225);
FORCEPROP 0 LAST ROOM DB1200Z
J 0
(-3375 4275);
DISPLAY 1.021277 (-3375 4275);
PAINT ORANGE (-3375 4275);
DISPLAY INVISIBLE (-3375 4275);
FORCEPROP 0 LAST BOM_COST SYS_CLOCK
J 0
(-3375 4375);
DISPLAY 1.021277 (-3375 4375);
PAINT ORANGE (-3375 4375);
DISPLAY INVISIBLE (-3375 4375);
FORCEADD GND..1
(-2800 3975);
FORCEPROP 3 LASTPIN (-2800 4025) SIG_NAME GND\g
J 0
(-2790 4035);
DISPLAY 0.659574 (-2790 4035);
PAINT MONO (-2790 4035);
DISPLAY INVISIBLE (-2790 4035);
FORCEPROP 1 LAST VOLTAGE 0.0V
J 0
(-2845 3932);
DISPLAY 0.340426 (-2845 3932);
PAINT SKYBLUE (-2845 3932);
DISPLAY INVISIBLE (-2845 3932);
FORCEPROP 1 LAST PATH I126
J 0
(-2725 3975);
DISPLAY 0.872340 (-2725 3975);
PAINT AQUA (-2725 3975);
DISPLAY INVISIBLE (-2725 3975);
FORCEPROP 1 LAST SIZE 1B
J 0
(-2725 3925);
DISPLAY 0.872340 (-2725 3925);
PAINT AQUA (-2725 3925);
DISPLAY INVISIBLE (-2725 3925);
FORCEPROP 2 LAST CDS_LIB mstr_symbols
J 0
(-2800 3975);
PAINT MONO (-2800 3975);
DISPLAY INVISIBLE (-2800 3975);
FORCEPROP 1 LAST BODY_TYPE PLUMBING
J 0
(-2845 3932);
DISPLAY 0.340426 (-2845 3932);
PAINT GREEN (-2845 3932);
DISPLAY INVISIBLE (-2845 3932);
FORCEPROP 1 LAST HDL_POWER GND
J 0
(-2800 4125);
DISPLAY 0.872340 (-2800 4125);
PAINT GREEN (-2800 4125);
DISPLAY INVISIBLE (-2800 4125);
FORCEADD RES..1
(-3325 3750);
FORCEPROP 1 LAST WATTAGE 1/16W
J 2
(-3350 3600);
DISPLAY 0.617021 (-3350 3600);
PAINT SKYBLUE (-3350 3600);
FORCEPROP 1 LAST VALUE 42.2
J 2
(-3350 3650);
DISPLAY 0.617021 (-3350 3650);
PAINT SKYBLUE (-3350 3650);
FORCEPROP 1 LAST LOCATION R7P7
J 0
(-3375 3800);
DISPLAY 0.617021 (-3375 3800);
PAINT AQUA (-3375 3800);
FORCEPROP 1 LAST TOLERANCE 1.0%
J 0
(-3325 3650);
DISPLAY 0.617021 (-3325 3650);
PAINT SKYBLUE (-3325 3650);
FORCEPROP 1 LAST MATERIAL EMPTY
J 0
(-3325 3600);
DISPLAY 0.617021 (-3325 3600);
PAINT RED (-3325 3600);
FORCEPROP 1 LAST PACK_TYPE 0402
J 0
(-3075 3600);
DISPLAY 0.617021 (-3075 3600);
PAINT SKYBLUE (-3075 3600);
FORCEPROP 1 LAST PART_NUMBER G21796-259
J 0
(-3175 3750);
DISPLAY 0.617021 (-3175 3750);
PAINT BLUE (-3175 3750);
FORCEPROP 1 LASTPIN (-3425 3750) $PN 1
J 0
(-3413 3762);
DISPLAY 0.787234 (-3413 3762);
PAINT ORANGE (-3413 3762);
DISPLAY INVISIBLE (-3413 3762);
FORCEPROP 2 LAST CDS_LOCATION R7P7
J 0
(-3375 3800);
DISPLAY 0.617021 (-3375 3800);
PAINT AQUA (-3375 3800);
DISPLAY INVISIBLE (-3375 3800);
FORCEPROP 1 LAST PATH I127
J 0
(-3375 3900);
DISPLAY 0.978723 (-3375 3900);
PAINT WHITE (-3375 3900);
DISPLAY INVISIBLE (-3375 3900);
FORCEPROP 0 LAST ROOM DB1200Z
J 0
(-3375 3950);
DISPLAY 1.021277 (-3375 3950);
PAINT ORANGE (-3375 3950);
DISPLAY INVISIBLE (-3375 3950);
FORCEPROP 2 LAST $SEC 1
J 0
(-3375 3950);
PAINT MONO (-3375 3950);
DISPLAY INVISIBLE (-3375 3950);
FORCEPROP 2 LAST CDS_SEC 1
J 0
(-3375 3950);
PAINT MONO (-3375 3950);
DISPLAY INVISIBLE (-3375 3950);
FORCEPROP 0 LAST BOM_COST SYS_CLOCK
J 0
(-3375 4050);
DISPLAY 1.021277 (-3375 4050);
PAINT ORANGE (-3375 4050);
DISPLAY INVISIBLE (-3375 4050);
FORCEPROP 2 LAST CDS_LIB mstr_discrete
J 0
(-3325 3750);
PAINT MONO (-3325 3750);
DISPLAY INVISIBLE (-3325 3750);
FORCEPROP 1 LASTPIN (-3225 3750) $PN 2
J 0
(-3263 3762);
DISPLAY 0.787234 (-3263 3762);
PAINT ORANGE (-3263 3762);
DISPLAY INVISIBLE (-3263 3762);
FORCEADD GND..1
(-2800 3650);
FORCEPROP 3 LASTPIN (-2800 3700) SIG_NAME GND\g
J 0
(-2790 3710);
DISPLAY 0.659574 (-2790 3710);
PAINT MONO (-2790 3710);
DISPLAY INVISIBLE (-2790 3710);
FORCEPROP 1 LAST VOLTAGE 0.0V
J 0
(-2845 3607);
DISPLAY 0.340426 (-2845 3607);
PAINT SKYBLUE (-2845 3607);
DISPLAY INVISIBLE (-2845 3607);
FORCEPROP 1 LAST SIZE 1B
J 0
(-2725 3600);
DISPLAY 0.872340 (-2725 3600);
PAINT AQUA (-2725 3600);
DISPLAY INVISIBLE (-2725 3600);
FORCEPROP 2 LAST CDS_LIB mstr_symbols
J 0
(-2800 3650);
PAINT MONO (-2800 3650);
DISPLAY INVISIBLE (-2800 3650);
FORCEPROP 1 LAST PATH I128
J 0
(-2725 3650);
DISPLAY 0.872340 (-2725 3650);
PAINT AQUA (-2725 3650);
DISPLAY INVISIBLE (-2725 3650);
FORCEPROP 1 LAST BODY_TYPE PLUMBING
J 0
(-2845 3607);
DISPLAY 0.340426 (-2845 3607);
PAINT GREEN (-2845 3607);
DISPLAY INVISIBLE (-2845 3607);
FORCEPROP 1 LAST HDL_POWER GND
J 0
(-2800 3800);
DISPLAY 0.872340 (-2800 3800);
PAINT GREEN (-2800 3800);
DISPLAY INVISIBLE (-2800 3800);
FORCEADD RES..1
(-3325 3425);
FORCEPROP 1 LAST WATTAGE 1/16W
J 2
(-3350 3275);
DISPLAY 0.617021 (-3350 3275);
PAINT SKYBLUE (-3350 3275);
FORCEPROP 1 LAST VALUE 42.2
J 2
(-3350 3325);
DISPLAY 0.617021 (-3350 3325);
PAINT SKYBLUE (-3350 3325);
FORCEPROP 1 LASTPIN (-3425 3425) $PN 1
J 0
(-3413 3437);
DISPLAY 0.617021 (-3413 3437);
PAINT ORANGE (-3413 3437);
FORCEPROP 1 LAST LOCATION R7P3
J 0
(-3375 3475);
DISPLAY 0.617021 (-3375 3475);
PAINT AQUA (-3375 3475);
FORCEPROP 1 LAST MATERIAL EMPTY
J 0
(-3325 3275);
DISPLAY 0.617021 (-3325 3275);
PAINT RED (-3325 3275);
FORCEPROP 1 LAST TOLERANCE 1.0%
J 0
(-3325 3325);
DISPLAY 0.617021 (-3325 3325);
PAINT SKYBLUE (-3325 3325);
FORCEPROP 1 LASTPIN (-3225 3425) $PN 2
J 0
(-3263 3437);
DISPLAY 0.617021 (-3263 3437);
PAINT ORANGE (-3263 3437);
FORCEPROP 1 LAST PACK_TYPE 0402
J 0
(-3075 3275);
DISPLAY 0.617021 (-3075 3275);
PAINT SKYBLUE (-3075 3275);
FORCEPROP 1 LAST PART_NUMBER G21796-259
J 0
(-3175 3425);
DISPLAY 0.617021 (-3175 3425);
PAINT BLUE (-3175 3425);
FORCEPROP 2 LAST CDS_LOCATION R7P3
J 0
(-3375 3475);
DISPLAY 0.617021 (-3375 3475);
PAINT AQUA (-3375 3475);
DISPLAY INVISIBLE (-3375 3475);
FORCEPROP 2 LAST CDS_LIB mstr_discrete
J 0
(-3325 3425);
PAINT MONO (-3325 3425);
DISPLAY INVISIBLE (-3325 3425);
FORCEPROP 1 LAST PATH I129
J 0
(-3375 3575);
DISPLAY 0.978723 (-3375 3575);
PAINT WHITE (-3375 3575);
DISPLAY INVISIBLE (-3375 3575);
FORCEPROP 0 LAST ROOM DB1200Z
J 0
(-3375 3625);
DISPLAY 1.021277 (-3375 3625);
PAINT ORANGE (-3375 3625);
DISPLAY INVISIBLE (-3375 3625);
FORCEPROP 2 LAST SEC 1
J 0
(-3375 3625);
DISPLAY 0.680851 (-3375 3625);
PAINT MONO (-3375 3625);
DISPLAY INVISIBLE (-3375 3625);
FORCEPROP 2 LAST SEC_TYPE 0402
J 0
(-3375 3625);
DISPLAY 1.021277 (-3375 3625);
PAINT ORANGE (-3375 3625);
DISPLAY INVISIBLE (-3375 3625);
FORCEPROP 0 LAST BOM_COST SYS_CLOCK
J 0
(-3375 3725);
DISPLAY 1.021277 (-3375 3725);
PAINT ORANGE (-3375 3725);
DISPLAY INVISIBLE (-3375 3725);
FORCEADD GND..1
(-2800 3325);
FORCEPROP 3 LASTPIN (-2800 3375) SIG_NAME GND\g
J 0
(-2790 3385);
DISPLAY 0.659574 (-2790 3385);
PAINT MONO (-2790 3385);
DISPLAY INVISIBLE (-2790 3385);
FORCEPROP 1 LAST VOLTAGE 0.0V
J 0
(-2845 3282);
DISPLAY 0.340426 (-2845 3282);
PAINT SKYBLUE (-2845 3282);
DISPLAY INVISIBLE (-2845 3282);
FORCEPROP 1 LAST SIZE 1B
J 0
(-2725 3275);
DISPLAY 0.872340 (-2725 3275);
PAINT AQUA (-2725 3275);
DISPLAY INVISIBLE (-2725 3275);
FORCEPROP 1 LAST PATH I130
J 0
(-2725 3325);
DISPLAY 0.872340 (-2725 3325);
PAINT AQUA (-2725 3325);
DISPLAY INVISIBLE (-2725 3325);
FORCEPROP 2 LAST CDS_LIB mstr_symbols
J 0
(-2800 3325);
PAINT MONO (-2800 3325);
DISPLAY INVISIBLE (-2800 3325);
FORCEPROP 1 LAST BODY_TYPE PLUMBING
J 0
(-2845 3282);
DISPLAY 0.340426 (-2845 3282);
PAINT GREEN (-2845 3282);
DISPLAY INVISIBLE (-2845 3282);
FORCEPROP 1 LAST HDL_POWER GND
J 0
(-2800 3475);
DISPLAY 0.872340 (-2800 3475);
PAINT GREEN (-2800 3475);
DISPLAY INVISIBLE (-2800 3475);
FORCEADD RES..1
(-3325 3100);
FORCEPROP 1 LAST WATTAGE 1/16W
J 2
(-3350 2950);
DISPLAY 0.617021 (-3350 2950);
PAINT SKYBLUE (-3350 2950);
FORCEPROP 1 LAST VALUE 42.2
J 2
(-3350 3000);
DISPLAY 0.617021 (-3350 3000);
PAINT SKYBLUE (-3350 3000);
FORCEPROP 1 LAST TOLERANCE 1.0%
J 0
(-3325 3000);
DISPLAY 0.617021 (-3325 3000);
PAINT SKYBLUE (-3325 3000);
FORCEPROP 1 LAST MATERIAL EMPTY
J 0
(-3325 2950);
DISPLAY 0.617021 (-3325 2950);
PAINT RED (-3325 2950);
FORCEPROP 1 LASTPIN (-3425 3100) $PN 1
J 0
(-3413 3112);
DISPLAY 0.617021 (-3413 3112);
PAINT ORANGE (-3413 3112);
FORCEPROP 1 LAST LOCATION R7P4
J 0
(-3375 3150);
DISPLAY 0.617021 (-3375 3150);
PAINT AQUA (-3375 3150);
FORCEPROP 1 LASTPIN (-3225 3100) $PN 2
J 0
(-3263 3112);
DISPLAY 0.617021 (-3263 3112);
PAINT ORANGE (-3263 3112);
FORCEPROP 1 LAST PACK_TYPE 0402
J 0
(-3075 2950);
DISPLAY 0.617021 (-3075 2950);
PAINT SKYBLUE (-3075 2950);
FORCEPROP 1 LAST PART_NUMBER G21796-259
J 0
(-3175 3100);
DISPLAY 0.617021 (-3175 3100);
PAINT BLUE (-3175 3100);
FORCEPROP 2 LAST CDS_LOCATION R7P4
J 0
(-3375 3150);
DISPLAY 0.617021 (-3375 3150);
PAINT AQUA (-3375 3150);
DISPLAY INVISIBLE (-3375 3150);
FORCEPROP 1 LAST PATH I131
J 0
(-3375 3250);
DISPLAY 0.978723 (-3375 3250);
PAINT WHITE (-3375 3250);
DISPLAY INVISIBLE (-3375 3250);
FORCEPROP 0 LAST ROOM DB1200Z
J 0
(-3375 3300);
DISPLAY 1.021277 (-3375 3300);
PAINT ORANGE (-3375 3300);
DISPLAY INVISIBLE (-3375 3300);
FORCEPROP 2 LAST SEC 1
J 0
(-3375 3300);
DISPLAY 0.680851 (-3375 3300);
PAINT MONO (-3375 3300);
DISPLAY INVISIBLE (-3375 3300);
FORCEPROP 2 LAST SEC_TYPE 0402
J 0
(-3375 3300);
DISPLAY 1.021277 (-3375 3300);
PAINT ORANGE (-3375 3300);
DISPLAY INVISIBLE (-3375 3300);
FORCEPROP 0 LAST BOM_COST SYS_CLOCK
J 0
(-3375 3400);
DISPLAY 1.021277 (-3375 3400);
PAINT ORANGE (-3375 3400);
DISPLAY INVISIBLE (-3375 3400);
FORCEPROP 2 LAST CDS_LIB mstr_discrete
J 0
(-3325 3100);
PAINT MONO (-3325 3100);
DISPLAY INVISIBLE (-3325 3100);
FORCEADD GND..1
(-2800 3000);
FORCEPROP 3 LASTPIN (-2800 3050) SIG_NAME GND\g
J 0
(-2790 3060);
DISPLAY 0.659574 (-2790 3060);
PAINT MONO (-2790 3060);
DISPLAY INVISIBLE (-2790 3060);
FORCEPROP 1 LAST VOLTAGE 0.0V
J 0
(-2845 2957);
DISPLAY 0.340426 (-2845 2957);
PAINT SKYBLUE (-2845 2957);
DISPLAY INVISIBLE (-2845 2957);
FORCEPROP 1 LAST PATH I132
J 0
(-2725 3000);
DISPLAY 0.872340 (-2725 3000);
PAINT AQUA (-2725 3000);
DISPLAY INVISIBLE (-2725 3000);
FORCEPROP 1 LAST SIZE 1B
J 0
(-2725 2950);
DISPLAY 0.872340 (-2725 2950);
PAINT AQUA (-2725 2950);
DISPLAY INVISIBLE (-2725 2950);
FORCEPROP 2 LAST CDS_LIB mstr_symbols
J 0
(-2800 3000);
PAINT MONO (-2800 3000);
DISPLAY INVISIBLE (-2800 3000);
FORCEPROP 1 LAST BODY_TYPE PLUMBING
J 0
(-2845 2957);
DISPLAY 0.340426 (-2845 2957);
PAINT GREEN (-2845 2957);
DISPLAY INVISIBLE (-2845 2957);
FORCEPROP 1 LAST HDL_POWER GND
J 0
(-2800 3150);
DISPLAY 0.872340 (-2800 3150);
PAINT GREEN (-2800 3150);
DISPLAY INVISIBLE (-2800 3150);
FORCEADD RES..1
(-3325 2775);
FORCEPROP 1 LAST WATTAGE 1/16W
J 2
(-3350 2625);
DISPLAY 0.617021 (-3350 2625);
PAINT SKYBLUE (-3350 2625);
FORCEPROP 1 LAST VALUE 42.2
J 2
(-3350 2675);
DISPLAY 0.617021 (-3350 2675);
PAINT SKYBLUE (-3350 2675);
FORCEPROP 1 LASTPIN (-3425 2775) $PN 1
J 0
(-3413 2787);
DISPLAY 0.617021 (-3413 2787);
PAINT ORANGE (-3413 2787);
FORCEPROP 1 LAST LOCATION R7P1
J 0
(-3375 2825);
DISPLAY 0.617021 (-3375 2825);
PAINT AQUA (-3375 2825);
FORCEPROP 1 LAST TOLERANCE 1.0%
J 0
(-3325 2675);
DISPLAY 0.617021 (-3325 2675);
PAINT SKYBLUE (-3325 2675);
FORCEPROP 1 LASTPIN (-3225 2775) $PN 2
J 0
(-3263 2787);
DISPLAY 0.617021 (-3263 2787);
PAINT ORANGE (-3263 2787);
FORCEPROP 1 LAST MATERIAL EMPTY
J 0
(-3325 2625);
DISPLAY 0.617021 (-3325 2625);
PAINT RED (-3325 2625);
FORCEPROP 1 LAST PACK_TYPE 0402
J 0
(-3075 2625);
DISPLAY 0.617021 (-3075 2625);
PAINT SKYBLUE (-3075 2625);
FORCEPROP 1 LAST PART_NUMBER G21796-259
J 0
(-3175 2775);
DISPLAY 0.617021 (-3175 2775);
PAINT BLUE (-3175 2775);
FORCEPROP 2 LAST CDS_LOCATION R7P1
J 0
(-3375 2825);
DISPLAY 0.617021 (-3375 2825);
PAINT AQUA (-3375 2825);
DISPLAY INVISIBLE (-3375 2825);
FORCEPROP 1 LAST PATH I133
J 0
(-3375 2925);
DISPLAY 0.978723 (-3375 2925);
PAINT WHITE (-3375 2925);
DISPLAY INVISIBLE (-3375 2925);
FORCEPROP 0 LAST ROOM DB1200Z
J 0
(-3375 2975);
DISPLAY 1.021277 (-3375 2975);
PAINT ORANGE (-3375 2975);
DISPLAY INVISIBLE (-3375 2975);
FORCEPROP 2 LAST SEC 1
J 0
(-3375 2975);
DISPLAY 0.680851 (-3375 2975);
PAINT MONO (-3375 2975);
DISPLAY INVISIBLE (-3375 2975);
FORCEPROP 2 LAST SEC_TYPE 0402
J 0
(-3375 2975);
DISPLAY 1.021277 (-3375 2975);
PAINT ORANGE (-3375 2975);
DISPLAY INVISIBLE (-3375 2975);
FORCEPROP 2 LAST CDS_LIB mstr_discrete
J 0
(-3325 2775);
PAINT MONO (-3325 2775);
DISPLAY INVISIBLE (-3325 2775);
FORCEPROP 0 LAST BOM_COST SYS_CLOCK
J 0
(-3375 3075);
DISPLAY 1.021277 (-3375 3075);
PAINT ORANGE (-3375 3075);
DISPLAY INVISIBLE (-3375 3075);
FORCEADD GND..1
(-2800 2675);
FORCEPROP 3 LASTPIN (-2800 2725) SIG_NAME GND\g
J 0
(-2790 2735);
DISPLAY 0.659574 (-2790 2735);
PAINT MONO (-2790 2735);
DISPLAY INVISIBLE (-2790 2735);
FORCEPROP 1 LAST VOLTAGE 0.0V
J 0
(-2845 2632);
DISPLAY 0.340426 (-2845 2632);
PAINT SKYBLUE (-2845 2632);
DISPLAY INVISIBLE (-2845 2632);
FORCEPROP 1 LAST PATH I134
J 0
(-2725 2675);
DISPLAY 0.872340 (-2725 2675);
PAINT AQUA (-2725 2675);
DISPLAY INVISIBLE (-2725 2675);
FORCEPROP 2 LAST CDS_LIB mstr_symbols
J 0
(-2800 2675);
PAINT MONO (-2800 2675);
DISPLAY INVISIBLE (-2800 2675);
FORCEPROP 1 LAST SIZE 1B
J 0
(-2725 2625);
DISPLAY 0.872340 (-2725 2625);
PAINT AQUA (-2725 2625);
DISPLAY INVISIBLE (-2725 2625);
FORCEPROP 1 LAST BODY_TYPE PLUMBING
J 0
(-2845 2632);
DISPLAY 0.340426 (-2845 2632);
PAINT GREEN (-2845 2632);
DISPLAY INVISIBLE (-2845 2632);
FORCEPROP 1 LAST HDL_POWER GND
J 0
(-2800 2825);
DISPLAY 0.872340 (-2800 2825);
PAINT GREEN (-2800 2825);
DISPLAY INVISIBLE (-2800 2825);
FORCEADD RES..1
(-3325 2450);
FORCEPROP 1 LAST WATTAGE 1/16W
J 2
(-3350 2300);
DISPLAY 0.617021 (-3350 2300);
PAINT SKYBLUE (-3350 2300);
FORCEPROP 1 LAST VALUE 42.2
J 2
(-3350 2350);
DISPLAY 0.617021 (-3350 2350);
PAINT SKYBLUE (-3350 2350);
FORCEPROP 1 LASTPIN (-3425 2450) $PN 1
J 0
(-3413 2462);
DISPLAY 0.617021 (-3413 2462);
PAINT ORANGE (-3413 2462);
FORCEPROP 1 LAST LOCATION R7P2
J 0
(-3375 2500);
DISPLAY 0.617021 (-3375 2500);
PAINT AQUA (-3375 2500);
FORCEPROP 1 LAST MATERIAL EMPTY
J 0
(-3325 2300);
DISPLAY 0.617021 (-3325 2300);
PAINT RED (-3325 2300);
FORCEPROP 1 LAST TOLERANCE 1.0%
J 0
(-3325 2350);
DISPLAY 0.617021 (-3325 2350);
PAINT SKYBLUE (-3325 2350);
FORCEPROP 1 LASTPIN (-3225 2450) $PN 2
J 0
(-3263 2462);
DISPLAY 0.617021 (-3263 2462);
PAINT ORANGE (-3263 2462);
FORCEPROP 1 LAST PACK_TYPE 0402
J 0
(-3075 2300);
DISPLAY 0.617021 (-3075 2300);
PAINT SKYBLUE (-3075 2300);
FORCEPROP 1 LAST PART_NUMBER G21796-259
J 0
(-3175 2450);
DISPLAY 0.617021 (-3175 2450);
PAINT BLUE (-3175 2450);
FORCEPROP 2 LAST CDS_LOCATION R7P2
J 0
(-3375 2500);
DISPLAY 0.617021 (-3375 2500);
PAINT AQUA (-3375 2500);
DISPLAY INVISIBLE (-3375 2500);
FORCEPROP 2 LAST CDS_LIB mstr_discrete
J 0
(-3325 2450);
PAINT MONO (-3325 2450);
DISPLAY INVISIBLE (-3325 2450);
FORCEPROP 1 LAST PATH I135
J 0
(-3375 2600);
DISPLAY 0.978723 (-3375 2600);
PAINT WHITE (-3375 2600);
DISPLAY INVISIBLE (-3375 2600);
FORCEPROP 2 LAST SEC 1
J 0
(-3375 2650);
DISPLAY 0.680851 (-3375 2650);
PAINT MONO (-3375 2650);
DISPLAY INVISIBLE (-3375 2650);
FORCEPROP 0 LAST ROOM DB1200Z
J 0
(-3375 2650);
DISPLAY 1.021277 (-3375 2650);
PAINT ORANGE (-3375 2650);
DISPLAY INVISIBLE (-3375 2650);
FORCEPROP 2 LAST SEC_TYPE 0402
J 0
(-3375 2650);
DISPLAY 1.021277 (-3375 2650);
PAINT ORANGE (-3375 2650);
DISPLAY INVISIBLE (-3375 2650);
FORCEPROP 0 LAST BOM_COST SYS_CLOCK
J 0
(-3375 2750);
DISPLAY 1.021277 (-3375 2750);
PAINT ORANGE (-3375 2750);
DISPLAY INVISIBLE (-3375 2750);
FORCEADD GND..1
(-2800 2350);
FORCEPROP 3 LASTPIN (-2800 2400) SIG_NAME GND\g
J 0
(-2790 2410);
DISPLAY 0.659574 (-2790 2410);
PAINT MONO (-2790 2410);
DISPLAY INVISIBLE (-2790 2410);
FORCEPROP 1 LAST VOLTAGE 0.0V
J 0
(-2845 2307);
DISPLAY 0.340426 (-2845 2307);
PAINT SKYBLUE (-2845 2307);
DISPLAY INVISIBLE (-2845 2307);
FORCEPROP 1 LAST SIZE 1B
J 0
(-2725 2300);
DISPLAY 0.872340 (-2725 2300);
PAINT AQUA (-2725 2300);
DISPLAY INVISIBLE (-2725 2300);
FORCEPROP 1 LAST PATH I136
J 0
(-2725 2350);
DISPLAY 0.872340 (-2725 2350);
PAINT AQUA (-2725 2350);
DISPLAY INVISIBLE (-2725 2350);
FORCEPROP 2 LAST CDS_LIB mstr_symbols
J 0
(-2800 2350);
PAINT MONO (-2800 2350);
DISPLAY INVISIBLE (-2800 2350);
FORCEPROP 1 LAST BODY_TYPE PLUMBING
J 0
(-2845 2307);
DISPLAY 0.340426 (-2845 2307);
PAINT GREEN (-2845 2307);
DISPLAY INVISIBLE (-2845 2307);
FORCEPROP 1 LAST HDL_POWER GND
J 0
(-2800 2500);
DISPLAY 0.872340 (-2800 2500);
PAINT GREEN (-2800 2500);
DISPLAY INVISIBLE (-2800 2500);
FORCEADD RES..1
(-3325 2125);
FORCEPROP 1 LAST WATTAGE 1/16W
J 2
(-3350 1975);
DISPLAY 0.617021 (-3350 1975);
PAINT SKYBLUE (-3350 1975);
FORCEPROP 1 LAST MATERIAL EMPTY
J 0
(-3325 1975);
DISPLAY 0.617021 (-3325 1975);
PAINT RED (-3325 1975);
FORCEPROP 1 LAST PACK_TYPE 0402
J 0
(-3075 1975);
DISPLAY 0.617021 (-3075 1975);
PAINT SKYBLUE (-3075 1975);
FORCEPROP 1 LAST TOLERANCE 1.0%
J 0
(-3325 2025);
DISPLAY 0.617021 (-3325 2025);
PAINT SKYBLUE (-3325 2025);
FORCEPROP 1 LAST VALUE 42.2
J 2
(-3350 2025);
DISPLAY 0.617021 (-3350 2025);
PAINT SKYBLUE (-3350 2025);
FORCEPROP 1 LASTPIN (-3425 2125) $PN 1
J 0
(-3413 2137);
DISPLAY 0.617021 (-3413 2137);
PAINT ORANGE (-3413 2137);
FORCEPROP 1 LAST LOCATION R6P7
J 0
(-3375 2175);
DISPLAY 0.617021 (-3375 2175);
PAINT AQUA (-3375 2175);
FORCEPROP 1 LASTPIN (-3225 2125) $PN 2
J 0
(-3263 2137);
DISPLAY 0.617021 (-3263 2137);
PAINT ORANGE (-3263 2137);
FORCEPROP 1 LAST PART_NUMBER G21796-259
J 0
(-3175 2125);
DISPLAY 0.617021 (-3175 2125);
PAINT BLUE (-3175 2125);
FORCEPROP 2 LAST CDS_LOCATION R6P7
J 0
(-3375 2175);
DISPLAY 0.617021 (-3375 2175);
PAINT AQUA (-3375 2175);
DISPLAY INVISIBLE (-3375 2175);
FORCEPROP 1 LAST PATH I137
J 0
(-3375 2275);
DISPLAY 0.978723 (-3375 2275);
PAINT WHITE (-3375 2275);
DISPLAY INVISIBLE (-3375 2275);
FORCEPROP 0 LAST ROOM DB1200Z
J 0
(-3375 2325);
DISPLAY 1.021277 (-3375 2325);
PAINT ORANGE (-3375 2325);
DISPLAY INVISIBLE (-3375 2325);
FORCEPROP 2 LAST SEC 1
J 0
(-3375 2325);
DISPLAY 0.680851 (-3375 2325);
PAINT MONO (-3375 2325);
DISPLAY INVISIBLE (-3375 2325);
FORCEPROP 2 LAST SEC_TYPE 0402
J 0
(-3375 2325);
DISPLAY 1.021277 (-3375 2325);
PAINT ORANGE (-3375 2325);
DISPLAY INVISIBLE (-3375 2325);
FORCEPROP 0 LAST BOM_COST SYS_CLOCK
J 0
(-3375 2425);
DISPLAY 1.021277 (-3375 2425);
PAINT ORANGE (-3375 2425);
DISPLAY INVISIBLE (-3375 2425);
FORCEPROP 2 LAST CDS_LIB mstr_discrete
J 0
(-3325 2125);
PAINT MONO (-3325 2125);
DISPLAY INVISIBLE (-3325 2125);
FORCEADD GND..1
(-2800 2025);
FORCEPROP 3 LASTPIN (-2800 2075) SIG_NAME GND\g
J 0
(-2790 2085);
DISPLAY 0.659574 (-2790 2085);
PAINT MONO (-2790 2085);
DISPLAY INVISIBLE (-2790 2085);
FORCEPROP 1 LAST VOLTAGE 0.0V
J 0
(-2845 1982);
DISPLAY 0.340426 (-2845 1982);
PAINT SKYBLUE (-2845 1982);
DISPLAY INVISIBLE (-2845 1982);
FORCEPROP 1 LAST SIZE 1B
J 0
(-2725 1975);
DISPLAY 0.872340 (-2725 1975);
PAINT AQUA (-2725 1975);
DISPLAY INVISIBLE (-2725 1975);
FORCEPROP 1 LAST PATH I138
J 0
(-2725 2025);
DISPLAY 0.872340 (-2725 2025);
PAINT AQUA (-2725 2025);
DISPLAY INVISIBLE (-2725 2025);
FORCEPROP 2 LAST CDS_LIB mstr_symbols
J 0
(-2800 2025);
PAINT MONO (-2800 2025);
DISPLAY INVISIBLE (-2800 2025);
FORCEPROP 1 LAST BODY_TYPE PLUMBING
J 0
(-2845 1982);
DISPLAY 0.340426 (-2845 1982);
PAINT GREEN (-2845 1982);
DISPLAY INVISIBLE (-2845 1982);
FORCEPROP 1 LAST HDL_POWER GND
J 0
(-2800 2175);
DISPLAY 0.872340 (-2800 2175);
PAINT GREEN (-2800 2175);
DISPLAY INVISIBLE (-2800 2175);
FORCEADD RES..1
(-3325 1800);
FORCEPROP 1 LAST WATTAGE 1/16W
J 2
(-3350 1650);
DISPLAY 0.617021 (-3350 1650);
PAINT SKYBLUE (-3350 1650);
FORCEPROP 1 LAST VALUE 42.2
J 2
(-3350 1700);
DISPLAY 0.617021 (-3350 1700);
PAINT SKYBLUE (-3350 1700);
FORCEPROP 1 LASTPIN (-3425 1800) $PN 1
J 0
(-3413 1812);
DISPLAY 0.617021 (-3413 1812);
PAINT ORANGE (-3413 1812);
FORCEPROP 1 LAST LOCATION R6P8
J 0
(-3375 1850);
DISPLAY 0.617021 (-3375 1850);
PAINT AQUA (-3375 1850);
FORCEPROP 1 LAST TOLERANCE 1.0%
J 0
(-3325 1700);
DISPLAY 0.617021 (-3325 1700);
PAINT SKYBLUE (-3325 1700);
FORCEPROP 1 LAST MATERIAL EMPTY
J 0
(-3325 1650);
DISPLAY 0.617021 (-3325 1650);
PAINT RED (-3325 1650);
FORCEPROP 1 LASTPIN (-3225 1800) $PN 2
J 0
(-3263 1812);
DISPLAY 0.617021 (-3263 1812);
PAINT ORANGE (-3263 1812);
FORCEPROP 1 LAST PACK_TYPE 0402
J 0
(-3075 1650);
DISPLAY 0.617021 (-3075 1650);
PAINT SKYBLUE (-3075 1650);
FORCEPROP 1 LAST PART_NUMBER G21796-259
J 0
(-3175 1800);
DISPLAY 0.617021 (-3175 1800);
PAINT BLUE (-3175 1800);
FORCEPROP 2 LAST CDS_LOCATION R6P8
J 0
(-3375 1850);
DISPLAY 0.617021 (-3375 1850);
PAINT AQUA (-3375 1850);
DISPLAY INVISIBLE (-3375 1850);
FORCEPROP 0 LAST ROOM DB1200Z
J 0
(-3375 2000);
DISPLAY 1.021277 (-3375 2000);
PAINT ORANGE (-3375 2000);
DISPLAY INVISIBLE (-3375 2000);
FORCEPROP 1 LAST PATH I139
J 0
(-3375 1950);
DISPLAY 0.978723 (-3375 1950);
PAINT WHITE (-3375 1950);
DISPLAY INVISIBLE (-3375 1950);
FORCEPROP 2 LAST SEC_TYPE 0402
J 0
(-3375 2000);
DISPLAY 1.021277 (-3375 2000);
PAINT ORANGE (-3375 2000);
DISPLAY INVISIBLE (-3375 2000);
FORCEPROP 2 LAST SEC 1
J 0
(-3375 2000);
DISPLAY 0.680851 (-3375 2000);
PAINT MONO (-3375 2000);
DISPLAY INVISIBLE (-3375 2000);
FORCEPROP 2 LAST CDS_LIB mstr_discrete
J 0
(-3325 1800);
PAINT MONO (-3325 1800);
DISPLAY INVISIBLE (-3325 1800);
FORCEPROP 0 LAST BOM_COST SYS_CLOCK
J 0
(-3375 2100);
DISPLAY 1.021277 (-3375 2100);
PAINT ORANGE (-3375 2100);
DISPLAY INVISIBLE (-3375 2100);
FORCEADD RES..1
(-3925 4525);
FORCEPROP 1 LAST VALUE 27.4
J 2
(-4000 4475);
DISPLAY 0.617021 (-4000 4475);
PAINT SKYBLUE (-4000 4475);
FORCEPROP 1 LASTPIN (-4025 4525) $PN 1
J 0
(-4013 4537);
DISPLAY 0.617021 (-4013 4537);
PAINT ORANGE (-4013 4537);
FORCEPROP 1 LAST WATTAGE 1/16W
J 2
(-3950 4425);
DISPLAY 0.617021 (-3950 4425);
PAINT SKYBLUE (-3950 4425);
FORCEPROP 1 LAST TOLERANCE 1%
J 0
(-3925 4425);
DISPLAY 0.617021 (-3925 4425);
PAINT SKYBLUE (-3925 4425);
FORCEPROP 1 LASTPIN (-3825 4525) $PN 2
J 0
(-3863 4537);
DISPLAY 0.617021 (-3863 4537);
PAINT ORANGE (-3863 4537);
FORCEPROP 1 LAST MATERIAL CHIP
J 0
(-3875 4475);
DISPLAY 0.617021 (-3875 4475);
PAINT SKYBLUE (-3875 4475);
FORCEPROP 1 LAST PACK_TYPE 0402
J 0
(-3850 4425);
DISPLAY 0.617021 (-3850 4425);
PAINT SKYBLUE (-3850 4425);
FORCEPROP 1 LAST PART_NUMBER G21796-182
J 0
(-4050 4375);
DISPLAY 0.617021 (-4050 4375);
PAINT BLUE (-4050 4375);
FORCEPROP 1 LAST LOCATION R4D28
J 0
(-3975 4575);
DISPLAY 0.617021 (-3975 4575);
PAINT AQUA (-3975 4575);
FORCEPROP 2 LAST CDS_LOCATION R4D28
J 0
(-3975 4575);
DISPLAY 0.617021 (-3975 4575);
PAINT AQUA (-3975 4575);
DISPLAY INVISIBLE (-3975 4575);
FORCEPROP 2 LAST CDS_LIB mstr_discrete
J 0
(-3925 4525);
PAINT ORANGE (-3925 4525);
DISPLAY INVISIBLE (-3925 4525);
FORCEPROP 0 LAST ROOM DB1200Z
J 0
(-3975 4675);
DISPLAY 1.021277 (-3975 4675);
PAINT ORANGE (-3975 4675);
DISPLAY INVISIBLE (-3975 4675);
FORCEPROP 1 LAST PATH I14
J 0
(-3975 4675);
DISPLAY 0.978723 (-3975 4675);
PAINT WHITE (-3975 4675);
DISPLAY INVISIBLE (-3975 4675);
FORCEPROP 2 LAST SEC 1
J 0
(-3975 4725);
DISPLAY 0.680851 (-3975 4725);
PAINT MONO (-3975 4725);
DISPLAY INVISIBLE (-3975 4725);
FORCEPROP 0 LAST BOM_COST SYS_CLOCK
J 0
(-3975 4775);
DISPLAY 1.021277 (-3975 4775);
PAINT ORANGE (-3975 4775);
DISPLAY INVISIBLE (-3975 4775);
FORCEPROP 2 LAST SEC_TYPE 0402
J 0
(-3975 4725);
DISPLAY 1.021277 (-3975 4725);
PAINT ORANGE (-3975 4725);
DISPLAY INVISIBLE (-3975 4725);
FORCEADD GND..1
(-2800 1700);
FORCEPROP 3 LASTPIN (-2800 1750) SIG_NAME GND\g
J 0
(-2790 1760);
DISPLAY 0.659574 (-2790 1760);
PAINT MONO (-2790 1760);
DISPLAY INVISIBLE (-2790 1760);
FORCEPROP 1 LAST VOLTAGE 0.0V
J 0
(-2845 1657);
DISPLAY 0.340426 (-2845 1657);
PAINT SKYBLUE (-2845 1657);
DISPLAY INVISIBLE (-2845 1657);
FORCEPROP 1 LAST PATH I140
J 0
(-2725 1700);
DISPLAY 0.872340 (-2725 1700);
PAINT AQUA (-2725 1700);
DISPLAY INVISIBLE (-2725 1700);
FORCEPROP 1 LAST SIZE 1B
J 0
(-2725 1650);
DISPLAY 0.872340 (-2725 1650);
PAINT AQUA (-2725 1650);
DISPLAY INVISIBLE (-2725 1650);
FORCEPROP 2 LAST CDS_LIB mstr_symbols
J 0
(-2800 1700);
PAINT MONO (-2800 1700);
DISPLAY INVISIBLE (-2800 1700);
FORCEPROP 1 LAST BODY_TYPE PLUMBING
J 0
(-2845 1657);
DISPLAY 0.340426 (-2845 1657);
PAINT GREEN (-2845 1657);
DISPLAY INVISIBLE (-2845 1657);
FORCEPROP 1 LAST HDL_POWER GND
J 0
(-2800 1850);
DISPLAY 0.872340 (-2800 1850);
PAINT GREEN (-2800 1850);
DISPLAY INVISIBLE (-2800 1850);
FORCEADD RES..1
(-3325 1475);
FORCEPROP 1 LAST WATTAGE 1/16W
J 2
(-3350 1325);
DISPLAY 0.617021 (-3350 1325);
PAINT SKYBLUE (-3350 1325);
FORCEPROP 1 LAST VALUE 42.2
J 2
(-3350 1375);
DISPLAY 0.617021 (-3350 1375);
PAINT SKYBLUE (-3350 1375);
FORCEPROP 1 LASTPIN (-3425 1475) $PN 1
J 0
(-3413 1487);
DISPLAY 0.617021 (-3413 1487);
PAINT ORANGE (-3413 1487);
FORCEPROP 1 LAST TOLERANCE 1.0%
J 0
(-3325 1375);
DISPLAY 0.617021 (-3325 1375);
PAINT SKYBLUE (-3325 1375);
FORCEPROP 1 LASTPIN (-3225 1475) $PN 2
J 0
(-3263 1487);
DISPLAY 0.617021 (-3263 1487);
PAINT ORANGE (-3263 1487);
FORCEPROP 1 LAST MATERIAL EMPTY
J 0
(-3325 1325);
DISPLAY 0.617021 (-3325 1325);
PAINT RED (-3325 1325);
FORCEPROP 1 LAST LOCATION R6P5
J 0
(-3375 1525);
DISPLAY 0.617021 (-3375 1525);
PAINT AQUA (-3375 1525);
FORCEPROP 1 LAST PACK_TYPE 0402
J 0
(-3075 1325);
DISPLAY 0.617021 (-3075 1325);
PAINT SKYBLUE (-3075 1325);
FORCEPROP 1 LAST PART_NUMBER G21796-259
J 0
(-3175 1475);
DISPLAY 0.617021 (-3175 1475);
PAINT BLUE (-3175 1475);
FORCEPROP 2 LAST CDS_LIB mstr_discrete
J 0
(-3325 1475);
PAINT MONO (-3325 1475);
DISPLAY INVISIBLE (-3325 1475);
FORCEPROP 2 LAST CDS_LOCATION R6P5
J 0
(-3375 1525);
DISPLAY 0.617021 (-3375 1525);
PAINT AQUA (-3375 1525);
DISPLAY INVISIBLE (-3375 1525);
FORCEPROP 1 LAST PATH I141
J 0
(-3375 1625);
DISPLAY 0.978723 (-3375 1625);
PAINT WHITE (-3375 1625);
DISPLAY INVISIBLE (-3375 1625);
FORCEPROP 0 LAST ROOM DB1200Z
J 0
(-3375 1675);
DISPLAY 1.021277 (-3375 1675);
PAINT ORANGE (-3375 1675);
DISPLAY INVISIBLE (-3375 1675);
FORCEPROP 2 LAST SEC 1
J 0
(-3375 1675);
DISPLAY 0.680851 (-3375 1675);
PAINT MONO (-3375 1675);
DISPLAY INVISIBLE (-3375 1675);
FORCEPROP 2 LAST SEC_TYPE 0402
J 0
(-3375 1675);
DISPLAY 1.021277 (-3375 1675);
PAINT ORANGE (-3375 1675);
DISPLAY INVISIBLE (-3375 1675);
FORCEPROP 0 LAST BOM_COST SYS_CLOCK
J 0
(-3375 1775);
DISPLAY 1.021277 (-3375 1775);
PAINT ORANGE (-3375 1775);
DISPLAY INVISIBLE (-3375 1775);
FORCEADD GND..1
(-2800 1375);
FORCEPROP 3 LASTPIN (-2800 1425) SIG_NAME GND\g
J 0
(-2790 1435);
DISPLAY 0.659574 (-2790 1435);
PAINT MONO (-2790 1435);
DISPLAY INVISIBLE (-2790 1435);
FORCEPROP 1 LAST VOLTAGE 0.0V
J 0
(-2845 1332);
DISPLAY 0.340426 (-2845 1332);
PAINT SKYBLUE (-2845 1332);
DISPLAY INVISIBLE (-2845 1332);
FORCEPROP 1 LAST PATH I142
J 0
(-2725 1375);
DISPLAY 0.872340 (-2725 1375);
PAINT AQUA (-2725 1375);
DISPLAY INVISIBLE (-2725 1375);
FORCEPROP 1 LAST SIZE 1B
J 0
(-2725 1325);
DISPLAY 0.872340 (-2725 1325);
PAINT AQUA (-2725 1325);
DISPLAY INVISIBLE (-2725 1325);
FORCEPROP 2 LAST CDS_LIB mstr_symbols
J 0
(-2800 1375);
PAINT MONO (-2800 1375);
DISPLAY INVISIBLE (-2800 1375);
FORCEPROP 1 LAST BODY_TYPE PLUMBING
J 0
(-2845 1332);
DISPLAY 0.340426 (-2845 1332);
PAINT GREEN (-2845 1332);
DISPLAY INVISIBLE (-2845 1332);
FORCEPROP 1 LAST HDL_POWER GND
J 0
(-2800 1525);
DISPLAY 0.872340 (-2800 1525);
PAINT GREEN (-2800 1525);
DISPLAY INVISIBLE (-2800 1525);
FORCEADD RES..1
(-3325 1150);
FORCEPROP 1 LAST WATTAGE 1/16W
J 2
(-3350 1000);
DISPLAY 0.617021 (-3350 1000);
PAINT SKYBLUE (-3350 1000);
FORCEPROP 1 LAST MATERIAL EMPTY
J 0
(-3325 1000);
DISPLAY 0.617021 (-3325 1000);
PAINT RED (-3325 1000);
FORCEPROP 1 LAST VALUE 42.2
J 2
(-3350 1050);
DISPLAY 0.617021 (-3350 1050);
PAINT SKYBLUE (-3350 1050);
FORCEPROP 1 LASTPIN (-3425 1150) $PN 1
J 0
(-3413 1162);
DISPLAY 0.617021 (-3413 1162);
PAINT ORANGE (-3413 1162);
FORCEPROP 1 LAST LOCATION R6P6
J 0
(-3375 1200);
DISPLAY 0.617021 (-3375 1200);
PAINT AQUA (-3375 1200);
FORCEPROP 1 LAST TOLERANCE 1.0%
J 0
(-3325 1050);
DISPLAY 0.617021 (-3325 1050);
PAINT SKYBLUE (-3325 1050);
FORCEPROP 1 LASTPIN (-3225 1150) $PN 2
J 0
(-3263 1162);
DISPLAY 0.617021 (-3263 1162);
PAINT ORANGE (-3263 1162);
FORCEPROP 1 LAST PACK_TYPE 0402
J 0
(-3075 1000);
DISPLAY 0.617021 (-3075 1000);
PAINT SKYBLUE (-3075 1000);
FORCEPROP 1 LAST PART_NUMBER G21796-259
J 0
(-3175 1150);
DISPLAY 0.617021 (-3175 1150);
PAINT BLUE (-3175 1150);
FORCEPROP 2 LAST CDS_LOCATION R6P6
J 0
(-3375 1200);
DISPLAY 0.617021 (-3375 1200);
PAINT AQUA (-3375 1200);
DISPLAY INVISIBLE (-3375 1200);
FORCEPROP 0 LAST ROOM DB1200Z
J 0
(-3375 1350);
DISPLAY 1.021277 (-3375 1350);
PAINT ORANGE (-3375 1350);
DISPLAY INVISIBLE (-3375 1350);
FORCEPROP 1 LAST PATH I143
J 0
(-3375 1300);
DISPLAY 0.978723 (-3375 1300);
PAINT WHITE (-3375 1300);
DISPLAY INVISIBLE (-3375 1300);
FORCEPROP 2 LAST SEC 1
J 0
(-3375 1350);
DISPLAY 0.680851 (-3375 1350);
PAINT MONO (-3375 1350);
DISPLAY INVISIBLE (-3375 1350);
FORCEPROP 2 LAST SEC_TYPE 0402
J 0
(-3375 1350);
DISPLAY 1.021277 (-3375 1350);
PAINT ORANGE (-3375 1350);
DISPLAY INVISIBLE (-3375 1350);
FORCEPROP 0 LAST BOM_COST SYS_CLOCK
J 0
(-3375 1450);
DISPLAY 1.021277 (-3375 1450);
PAINT ORANGE (-3375 1450);
DISPLAY INVISIBLE (-3375 1450);
FORCEPROP 2 LAST CDS_LIB mstr_discrete
J 0
(-3325 1150);
PAINT MONO (-3325 1150);
DISPLAY INVISIBLE (-3325 1150);
FORCEADD GND..1
(-2800 1050);
FORCEPROP 3 LASTPIN (-2800 1100) SIG_NAME GND\g
J 0
(-2790 1110);
DISPLAY 0.659574 (-2790 1110);
PAINT MONO (-2790 1110);
DISPLAY INVISIBLE (-2790 1110);
FORCEPROP 1 LAST VOLTAGE 0.0V
J 0
(-2845 1007);
DISPLAY 0.340426 (-2845 1007);
PAINT SKYBLUE (-2845 1007);
DISPLAY INVISIBLE (-2845 1007);
FORCEPROP 1 LAST SIZE 1B
J 0
(-2725 1000);
DISPLAY 0.872340 (-2725 1000);
PAINT AQUA (-2725 1000);
DISPLAY INVISIBLE (-2725 1000);
FORCEPROP 2 LAST CDS_LIB mstr_symbols
J 0
(-2800 1050);
PAINT MONO (-2800 1050);
DISPLAY INVISIBLE (-2800 1050);
FORCEPROP 1 LAST PATH I144
J 0
(-2725 1050);
DISPLAY 0.872340 (-2725 1050);
PAINT AQUA (-2725 1050);
DISPLAY INVISIBLE (-2725 1050);
FORCEPROP 1 LAST BODY_TYPE PLUMBING
J 0
(-2845 1007);
DISPLAY 0.340426 (-2845 1007);
PAINT GREEN (-2845 1007);
DISPLAY INVISIBLE (-2845 1007);
FORCEPROP 1 LAST HDL_POWER GND
J 0
(-2800 1200);
DISPLAY 0.872340 (-2800 1200);
PAINT GREEN (-2800 1200);
DISPLAY INVISIBLE (-2800 1200);
FORCEADD RES..1
(1025 4725);
FORCEPROP 1 LAST WATTAGE 1/16W
J 2
(1000 4575);
DISPLAY 0.617021 (1000 4575);
PAINT SKYBLUE (1000 4575);
FORCEPROP 1 LAST VALUE 42.2
J 2
(1000 4625);
DISPLAY 0.617021 (1000 4625);
PAINT SKYBLUE (1000 4625);
FORCEPROP 1 LASTPIN (925 4725) $PN 1
J 0
(937 4737);
DISPLAY 0.617021 (937 4737);
PAINT ORANGE (937 4737);
FORCEPROP 1 LAST LOCATION R6P3
J 0
(975 4775);
DISPLAY 0.617021 (975 4775);
PAINT AQUA (975 4775);
FORCEPROP 1 LAST MATERIAL EMPTY
J 0
(1025 4575);
DISPLAY 0.617021 (1025 4575);
PAINT RED (1025 4575);
FORCEPROP 1 LAST TOLERANCE 1.0%
J 0
(1025 4625);
DISPLAY 0.617021 (1025 4625);
PAINT SKYBLUE (1025 4625);
FORCEPROP 1 LASTPIN (1125 4725) $PN 2
J 0
(1087 4737);
DISPLAY 0.617021 (1087 4737);
PAINT ORANGE (1087 4737);
FORCEPROP 1 LAST PART_NUMBER G21796-259
J 0
(1175 4725);
DISPLAY 0.617021 (1175 4725);
PAINT BLUE (1175 4725);
FORCEPROP 1 LAST PACK_TYPE 0402
J 0
(1275 4575);
DISPLAY 0.617021 (1275 4575);
PAINT SKYBLUE (1275 4575);
FORCEPROP 2 LAST CDS_LOCATION R6P3
J 0
(975 4775);
DISPLAY 0.617021 (975 4775);
PAINT AQUA (975 4775);
DISPLAY INVISIBLE (975 4775);
FORCEPROP 0 LAST ROOM DB1200Z
J 0
(975 4925);
DISPLAY 1.021277 (975 4925);
PAINT ORANGE (975 4925);
DISPLAY INVISIBLE (975 4925);
FORCEPROP 1 LAST PATH I145
J 0
(975 4875);
DISPLAY 0.978723 (975 4875);
PAINT WHITE (975 4875);
DISPLAY INVISIBLE (975 4875);
FORCEPROP 2 LAST SEC 1
J 0
(975 4925);
DISPLAY 0.680851 (975 4925);
PAINT MONO (975 4925);
DISPLAY INVISIBLE (975 4925);
FORCEPROP 0 LAST BOM_COST SYS_CLOCK
J 0
(975 5025);
DISPLAY 1.021277 (975 5025);
PAINT ORANGE (975 5025);
DISPLAY INVISIBLE (975 5025);
FORCEPROP 2 LAST SEC_TYPE 0402
J 0
(975 4925);
DISPLAY 1.021277 (975 4925);
PAINT ORANGE (975 4925);
DISPLAY INVISIBLE (975 4925);
FORCEPROP 2 LAST CDS_LIB mstr_discrete
J 0
(1025 4725);
PAINT MONO (1025 4725);
DISPLAY INVISIBLE (1025 4725);
FORCEADD GND..1
(1550 4625);
FORCEPROP 3 LASTPIN (1550 4675) SIG_NAME GND\g
J 0
(1560 4685);
DISPLAY 0.659574 (1560 4685);
PAINT MONO (1560 4685);
DISPLAY INVISIBLE (1560 4685);
FORCEPROP 1 LAST VOLTAGE 0.0V
J 0
(1505 4582);
DISPLAY 0.340426 (1505 4582);
PAINT SKYBLUE (1505 4582);
DISPLAY INVISIBLE (1505 4582);
FORCEPROP 1 LAST SIZE 1B
J 0
(1625 4575);
DISPLAY 0.872340 (1625 4575);
PAINT AQUA (1625 4575);
DISPLAY INVISIBLE (1625 4575);
FORCEPROP 2 LAST CDS_LIB mstr_symbols
J 0
(1550 4625);
PAINT MONO (1550 4625);
DISPLAY INVISIBLE (1550 4625);
FORCEPROP 1 LAST PATH I146
J 0
(1625 4625);
DISPLAY 0.872340 (1625 4625);
PAINT AQUA (1625 4625);
DISPLAY INVISIBLE (1625 4625);
FORCEPROP 1 LAST BODY_TYPE PLUMBING
J 0
(1505 4582);
DISPLAY 0.340426 (1505 4582);
PAINT GREEN (1505 4582);
DISPLAY INVISIBLE (1505 4582);
FORCEPROP 1 LAST HDL_POWER GND
J 0
(1550 4775);
DISPLAY 0.872340 (1550 4775);
PAINT GREEN (1550 4775);
DISPLAY INVISIBLE (1550 4775);
FORCEADD RES..1
(1050 4400);
FORCEPROP 1 LASTPIN (950 4400) $PN 1
J 0
(962 4412);
DISPLAY 0.617021 (962 4412);
PAINT ORANGE (962 4412);
FORCEPROP 1 LAST WATTAGE 1/16W
J 2
(1025 4250);
DISPLAY 0.617021 (1025 4250);
PAINT SKYBLUE (1025 4250);
FORCEPROP 1 LAST VALUE 42.2
J 2
(1025 4300);
DISPLAY 0.617021 (1025 4300);
PAINT SKYBLUE (1025 4300);
FORCEPROP 1 LAST LOCATION R6P4
J 0
(1000 4450);
DISPLAY 0.617021 (1000 4450);
PAINT AQUA (1000 4450);
FORCEPROP 1 LAST TOLERANCE 1.0%
J 0
(1050 4300);
DISPLAY 0.617021 (1050 4300);
PAINT SKYBLUE (1050 4300);
FORCEPROP 1 LAST MATERIAL EMPTY
J 0
(1050 4250);
DISPLAY 0.617021 (1050 4250);
PAINT RED (1050 4250);
FORCEPROP 1 LASTPIN (1150 4400) $PN 2
J 0
(1112 4412);
DISPLAY 0.617021 (1112 4412);
PAINT ORANGE (1112 4412);
FORCEPROP 1 LAST PART_NUMBER G21796-259
J 0
(1200 4400);
DISPLAY 0.617021 (1200 4400);
PAINT BLUE (1200 4400);
FORCEPROP 1 LAST PACK_TYPE 0402
J 0
(1300 4250);
DISPLAY 0.617021 (1300 4250);
PAINT SKYBLUE (1300 4250);
FORCEPROP 2 LAST CDS_LOCATION R6P4
J 0
(1000 4450);
DISPLAY 0.617021 (1000 4450);
PAINT AQUA (1000 4450);
DISPLAY INVISIBLE (1000 4450);
FORCEPROP 1 LAST PATH I147
J 0
(1000 4550);
DISPLAY 0.978723 (1000 4550);
PAINT WHITE (1000 4550);
DISPLAY INVISIBLE (1000 4550);
FORCEPROP 0 LAST ROOM DB1200Z
J 0
(1000 4600);
DISPLAY 1.021277 (1000 4600);
PAINT ORANGE (1000 4600);
DISPLAY INVISIBLE (1000 4600);
FORCEPROP 2 LAST SEC 1
J 0
(1000 4600);
DISPLAY 0.680851 (1000 4600);
PAINT MONO (1000 4600);
DISPLAY INVISIBLE (1000 4600);
FORCEPROP 2 LAST SEC_TYPE 0402
J 0
(1000 4600);
DISPLAY 1.021277 (1000 4600);
PAINT ORANGE (1000 4600);
DISPLAY INVISIBLE (1000 4600);
FORCEPROP 0 LAST BOM_COST SYS_CLOCK
J 0
(1000 4700);
DISPLAY 1.021277 (1000 4700);
PAINT ORANGE (1000 4700);
DISPLAY INVISIBLE (1000 4700);
FORCEPROP 2 LAST CDS_LIB mstr_discrete
J 0
(1050 4400);
PAINT MONO (1050 4400);
DISPLAY INVISIBLE (1050 4400);
FORCEADD GND..1
(1575 4300);
FORCEPROP 3 LASTPIN (1575 4350) SIG_NAME GND\g
J 0
(1585 4360);
DISPLAY 0.659574 (1585 4360);
PAINT MONO (1585 4360);
DISPLAY INVISIBLE (1585 4360);
FORCEPROP 1 LAST VOLTAGE 0.0V
J 0
(1530 4257);
DISPLAY 0.340426 (1530 4257);
PAINT SKYBLUE (1530 4257);
DISPLAY INVISIBLE (1530 4257);
FORCEPROP 1 LAST SIZE 1B
J 0
(1650 4250);
DISPLAY 0.872340 (1650 4250);
PAINT AQUA (1650 4250);
DISPLAY INVISIBLE (1650 4250);
FORCEPROP 2 LAST CDS_LIB mstr_symbols
J 0
(1575 4300);
PAINT MONO (1575 4300);
DISPLAY INVISIBLE (1575 4300);
FORCEPROP 1 LAST PATH I148
J 0
(1650 4300);
DISPLAY 0.872340 (1650 4300);
PAINT AQUA (1650 4300);
DISPLAY INVISIBLE (1650 4300);
FORCEPROP 1 LAST BODY_TYPE PLUMBING
J 0
(1530 4257);
DISPLAY 0.340426 (1530 4257);
PAINT GREEN (1530 4257);
DISPLAY INVISIBLE (1530 4257);
FORCEPROP 1 LAST HDL_POWER GND
J 0
(1575 4450);
DISPLAY 0.872340 (1575 4450);
PAINT GREEN (1575 4450);
DISPLAY INVISIBLE (1575 4450);
FORCEADD RES..1
(1025 4075);
FORCEPROP 1 LAST MATERIAL EMPTY
J 0
(1025 3925);
DISPLAY 0.617021 (1025 3925);
PAINT RED (1025 3925);
FORCEPROP 1 LAST WATTAGE 1/16W
J 2
(1000 3925);
DISPLAY 0.617021 (1000 3925);
PAINT SKYBLUE (1000 3925);
FORCEPROP 1 LAST VALUE 42.2
J 2
(1000 3975);
DISPLAY 0.617021 (1000 3975);
PAINT SKYBLUE (1000 3975);
FORCEPROP 1 LAST TOLERANCE 1.0%
J 0
(1025 3975);
DISPLAY 0.617021 (1025 3975);
PAINT SKYBLUE (1025 3975);
FORCEPROP 1 LAST PACK_TYPE 0402
J 0
(1275 3925);
DISPLAY 0.617021 (1275 3925);
PAINT SKYBLUE (1275 3925);
FORCEPROP 1 LASTPIN (925 4075) $PN 1
J 0
(937 4087);
DISPLAY 0.617021 (937 4087);
PAINT ORANGE (937 4087);
FORCEPROP 1 LASTPIN (1125 4075) $PN 2
J 0
(1087 4087);
DISPLAY 0.617021 (1087 4087);
PAINT ORANGE (1087 4087);
FORCEPROP 1 LAST PART_NUMBER G21796-259
J 0
(1175 4075);
DISPLAY 0.617021 (1175 4075);
PAINT BLUE (1175 4075);
FORCEPROP 1 LAST LOCATION R6P1
J 0
(975 4125);
DISPLAY 0.617021 (975 4125);
PAINT AQUA (975 4125);
FORCEPROP 2 LAST CDS_LIB mstr_discrete
J 0
(1025 4075);
PAINT MONO (1025 4075);
DISPLAY INVISIBLE (1025 4075);
FORCEPROP 2 LAST CDS_LOCATION R6P1
J 0
(975 4125);
DISPLAY 0.617021 (975 4125);
PAINT AQUA (975 4125);
DISPLAY INVISIBLE (975 4125);
FORCEPROP 0 LAST ROOM DB1200Z
J 0
(975 4275);
DISPLAY 1.021277 (975 4275);
PAINT ORANGE (975 4275);
DISPLAY INVISIBLE (975 4275);
FORCEPROP 1 LAST PATH I149
J 0
(975 4225);
DISPLAY 0.978723 (975 4225);
PAINT WHITE (975 4225);
DISPLAY INVISIBLE (975 4225);
FORCEPROP 2 LAST SEC 1
J 0
(975 4275);
DISPLAY 0.680851 (975 4275);
PAINT MONO (975 4275);
DISPLAY INVISIBLE (975 4275);
FORCEPROP 2 LAST SEC_TYPE 0402
J 0
(975 4275);
DISPLAY 1.021277 (975 4275);
PAINT ORANGE (975 4275);
DISPLAY INVISIBLE (975 4275);
FORCEPROP 0 LAST BOM_COST SYS_CLOCK
J 0
(975 4375);
DISPLAY 1.021277 (975 4375);
PAINT ORANGE (975 4375);
DISPLAY INVISIBLE (975 4375);
FORCEADD OFFPAGE..1
(-4900 4525);
FORCEPROP 2 LAST $XR0 102 
J 0
(-5152 4525);
DISPLAY 0.638298 (-5152 4525);
PAINT MONO (-5152 4525);
FORCEPROP 2 LAST CDS_LIB mstr_standard
J 0
(-4900 4525);
PAINT ORANGE (-4900 4525);
DISPLAY INVISIBLE (-4900 4525);
FORCEPROP 2 LAST PATH I15
J 0
(-4850 4600);
DISPLAY 1.021277 (-4850 4600);
PAINT ORANGE (-4850 4600);
DISPLAY INVISIBLE (-4850 4600);
FORCEPROP 1 LAST OFFPAGE TRUE
J 0
(-4575 4400);
DISPLAY 0.872340 (-4575 4400);
PAINT GREEN (-4575 4400);
DISPLAY INVISIBLE (-4575 4400);
FORCEPROP 1 LAST COMMENT_BODY TRUE
J 0
(-4775 4425);
DISPLAY 0.872340 (-4775 4425);
PAINT GREEN (-4775 4425);
DISPLAY INVISIBLE (-4775 4425);
FORCEADD GND..1
(1550 3975);
FORCEPROP 3 LASTPIN (1550 4025) SIG_NAME GND\g
J 0
(1560 4035);
DISPLAY 0.659574 (1560 4035);
PAINT MONO (1560 4035);
DISPLAY INVISIBLE (1560 4035);
FORCEPROP 1 LAST VOLTAGE 0.0V
J 0
(1505 3932);
DISPLAY 0.340426 (1505 3932);
PAINT SKYBLUE (1505 3932);
DISPLAY INVISIBLE (1505 3932);
FORCEPROP 1 LAST PATH I150
J 0
(1625 3975);
DISPLAY 0.872340 (1625 3975);
PAINT AQUA (1625 3975);
DISPLAY INVISIBLE (1625 3975);
FORCEPROP 1 LAST SIZE 1B
J 0
(1625 3925);
DISPLAY 0.872340 (1625 3925);
PAINT AQUA (1625 3925);
DISPLAY INVISIBLE (1625 3925);
FORCEPROP 2 LAST CDS_LIB mstr_symbols
J 0
(1550 3975);
PAINT MONO (1550 3975);
DISPLAY INVISIBLE (1550 3975);
FORCEPROP 1 LAST BODY_TYPE PLUMBING
J 0
(1505 3932);
DISPLAY 0.340426 (1505 3932);
PAINT GREEN (1505 3932);
DISPLAY INVISIBLE (1505 3932);
FORCEPROP 1 LAST HDL_POWER GND
J 0
(1550 4125);
DISPLAY 0.872340 (1550 4125);
PAINT GREEN (1550 4125);
DISPLAY INVISIBLE (1550 4125);
FORCEADD RES..1
(1050 3750);
FORCEPROP 1 LASTPIN (950 3750) $PN 1
J 0
(962 3762);
DISPLAY 0.617021 (962 3762);
PAINT ORANGE (962 3762);
FORCEPROP 1 LAST WATTAGE 1/16W
J 2
(1025 3600);
DISPLAY 0.617021 (1025 3600);
PAINT SKYBLUE (1025 3600);
FORCEPROP 1 LAST VALUE 42.2
J 2
(1025 3650);
DISPLAY 0.617021 (1025 3650);
PAINT SKYBLUE (1025 3650);
FORCEPROP 1 LAST LOCATION R6P2
J 0
(1000 3800);
DISPLAY 0.617021 (1000 3800);
PAINT AQUA (1000 3800);
FORCEPROP 1 LASTPIN (1150 3750) $PN 2
J 0
(1112 3762);
DISPLAY 0.617021 (1112 3762);
PAINT ORANGE (1112 3762);
FORCEPROP 1 LAST TOLERANCE 1.0%
J 0
(1050 3650);
DISPLAY 0.617021 (1050 3650);
PAINT SKYBLUE (1050 3650);
FORCEPROP 1 LAST MATERIAL EMPTY
J 0
(1050 3600);
DISPLAY 0.617021 (1050 3600);
PAINT RED (1050 3600);
FORCEPROP 1 LAST PART_NUMBER G21796-259
J 0
(1200 3750);
DISPLAY 0.617021 (1200 3750);
PAINT BLUE (1200 3750);
FORCEPROP 1 LAST PACK_TYPE 0402
J 0
(1300 3600);
DISPLAY 0.617021 (1300 3600);
PAINT SKYBLUE (1300 3600);
FORCEPROP 2 LAST CDS_LOCATION R6P2
J 0
(1000 3800);
DISPLAY 0.617021 (1000 3800);
PAINT AQUA (1000 3800);
DISPLAY INVISIBLE (1000 3800);
FORCEPROP 1 LAST PATH I151
J 0
(1000 3900);
DISPLAY 0.978723 (1000 3900);
PAINT WHITE (1000 3900);
DISPLAY INVISIBLE (1000 3900);
FORCEPROP 0 LAST ROOM DB1200Z
J 0
(1000 3950);
DISPLAY 1.021277 (1000 3950);
PAINT ORANGE (1000 3950);
DISPLAY INVISIBLE (1000 3950);
FORCEPROP 2 LAST SEC 1
J 0
(1000 3950);
DISPLAY 0.680851 (1000 3950);
PAINT MONO (1000 3950);
DISPLAY INVISIBLE (1000 3950);
FORCEPROP 2 LAST SEC_TYPE 0402
J 0
(1000 3950);
DISPLAY 1.021277 (1000 3950);
PAINT ORANGE (1000 3950);
DISPLAY INVISIBLE (1000 3950);
FORCEPROP 0 LAST BOM_COST SYS_CLOCK
J 0
(1000 4050);
DISPLAY 1.021277 (1000 4050);
PAINT ORANGE (1000 4050);
DISPLAY INVISIBLE (1000 4050);
FORCEPROP 2 LAST CDS_LIB mstr_discrete
J 0
(1050 3750);
PAINT MONO (1050 3750);
DISPLAY INVISIBLE (1050 3750);
FORCEADD GND..1
(1575 3650);
FORCEPROP 3 LASTPIN (1575 3700) SIG_NAME GND\g
J 0
(1585 3710);
DISPLAY 0.659574 (1585 3710);
PAINT MONO (1585 3710);
DISPLAY INVISIBLE (1585 3710);
FORCEPROP 1 LAST VOLTAGE 0.0V
J 0
(1530 3607);
DISPLAY 0.340426 (1530 3607);
PAINT SKYBLUE (1530 3607);
DISPLAY INVISIBLE (1530 3607);
FORCEPROP 1 LAST SIZE 1B
J 0
(1650 3600);
DISPLAY 0.872340 (1650 3600);
PAINT AQUA (1650 3600);
DISPLAY INVISIBLE (1650 3600);
FORCEPROP 2 LAST CDS_LIB mstr_symbols
J 0
(1575 3650);
PAINT MONO (1575 3650);
DISPLAY INVISIBLE (1575 3650);
FORCEPROP 1 LAST PATH I152
J 0
(1650 3650);
DISPLAY 0.872340 (1650 3650);
PAINT AQUA (1650 3650);
DISPLAY INVISIBLE (1650 3650);
FORCEPROP 1 LAST BODY_TYPE PLUMBING
J 0
(1530 3607);
DISPLAY 0.340426 (1530 3607);
PAINT GREEN (1530 3607);
DISPLAY INVISIBLE (1530 3607);
FORCEPROP 1 LAST HDL_POWER GND
J 0
(1575 3800);
DISPLAY 0.872340 (1575 3800);
PAINT GREEN (1575 3800);
DISPLAY INVISIBLE (1575 3800);
FORCEADD RES..1
(1050 3425);
FORCEPROP 1 LASTPIN (950 3425) $PN 1
J 0
(962 3437);
DISPLAY 0.617021 (962 3437);
PAINT ORANGE (962 3437);
FORCEPROP 1 LAST WATTAGE 1/16W
J 2
(1025 3275);
DISPLAY 0.617021 (1025 3275);
PAINT SKYBLUE (1025 3275);
FORCEPROP 1 LAST VALUE 42.2
J 2
(1025 3325);
DISPLAY 0.617021 (1025 3325);
PAINT SKYBLUE (1025 3325);
FORCEPROP 1 LAST LOCATION R6P11
J 0
(1000 3475);
DISPLAY 0.617021 (1000 3475);
PAINT AQUA (1000 3475);
FORCEPROP 1 LAST MATERIAL EMPTY
J 0
(1050 3275);
DISPLAY 0.617021 (1050 3275);
PAINT RED (1050 3275);
FORCEPROP 1 LAST TOLERANCE 1.0%
J 0
(1050 3325);
DISPLAY 0.617021 (1050 3325);
PAINT SKYBLUE (1050 3325);
FORCEPROP 1 LASTPIN (1150 3425) $PN 2
J 0
(1112 3437);
DISPLAY 0.617021 (1112 3437);
PAINT ORANGE (1112 3437);
FORCEPROP 1 LAST PART_NUMBER G21796-259
J 0
(1200 3425);
DISPLAY 0.617021 (1200 3425);
PAINT BLUE (1200 3425);
FORCEPROP 1 LAST PACK_TYPE 0402
J 0
(1300 3275);
DISPLAY 0.617021 (1300 3275);
PAINT SKYBLUE (1300 3275);
FORCEPROP 2 LAST CDS_LOCATION R6P11
J 0
(1000 3475);
DISPLAY 0.617021 (1000 3475);
PAINT AQUA (1000 3475);
DISPLAY INVISIBLE (1000 3475);
FORCEPROP 1 LAST PATH I153
J 0
(1000 3575);
DISPLAY 0.978723 (1000 3575);
PAINT WHITE (1000 3575);
DISPLAY INVISIBLE (1000 3575);
FORCEPROP 0 LAST ROOM DB1200Z
J 0
(1000 3625);
DISPLAY 1.021277 (1000 3625);
PAINT ORANGE (1000 3625);
DISPLAY INVISIBLE (1000 3625);
FORCEPROP 2 LAST SEC 1
J 0
(1000 3625);
DISPLAY 0.680851 (1000 3625);
PAINT MONO (1000 3625);
DISPLAY INVISIBLE (1000 3625);
FORCEPROP 2 LAST SEC_TYPE 0402
J 0
(1000 3625);
DISPLAY 1.021277 (1000 3625);
PAINT ORANGE (1000 3625);
DISPLAY INVISIBLE (1000 3625);
FORCEPROP 0 LAST BOM_COST SYS_CLOCK
J 0
(1000 3725);
DISPLAY 1.021277 (1000 3725);
PAINT ORANGE (1000 3725);
DISPLAY INVISIBLE (1000 3725);
FORCEPROP 2 LAST CDS_LIB mstr_discrete
J 0
(1050 3425);
PAINT MONO (1050 3425);
DISPLAY INVISIBLE (1050 3425);
FORCEADD GND..1
(1575 3325);
FORCEPROP 3 LASTPIN (1575 3375) SIG_NAME GND\g
J 0
(1585 3385);
DISPLAY 0.659574 (1585 3385);
PAINT MONO (1585 3385);
DISPLAY INVISIBLE (1585 3385);
FORCEPROP 1 LAST VOLTAGE 0.0V
J 0
(1530 3282);
DISPLAY 0.340426 (1530 3282);
PAINT SKYBLUE (1530 3282);
DISPLAY INVISIBLE (1530 3282);
FORCEPROP 1 LAST SIZE 1B
J 0
(1650 3275);
DISPLAY 0.872340 (1650 3275);
PAINT AQUA (1650 3275);
DISPLAY INVISIBLE (1650 3275);
FORCEPROP 2 LAST CDS_LIB mstr_symbols
J 0
(1575 3325);
PAINT MONO (1575 3325);
DISPLAY INVISIBLE (1575 3325);
FORCEPROP 1 LAST PATH I154
J 0
(1650 3325);
DISPLAY 0.872340 (1650 3325);
PAINT AQUA (1650 3325);
DISPLAY INVISIBLE (1650 3325);
FORCEPROP 1 LAST BODY_TYPE PLUMBING
J 0
(1530 3282);
DISPLAY 0.340426 (1530 3282);
PAINT GREEN (1530 3282);
DISPLAY INVISIBLE (1530 3282);
FORCEPROP 1 LAST HDL_POWER GND
J 0
(1575 3475);
DISPLAY 0.872340 (1575 3475);
PAINT GREEN (1575 3475);
DISPLAY INVISIBLE (1575 3475);
FORCEADD RES..1
(1075 3100);
FORCEPROP 1 LASTPIN (975 3100) $PN 1
J 0
(987 3112);
DISPLAY 0.617021 (987 3112);
PAINT ORANGE (987 3112);
FORCEPROP 1 LAST WATTAGE 1/16W
J 2
(1050 2950);
DISPLAY 0.617021 (1050 2950);
PAINT SKYBLUE (1050 2950);
FORCEPROP 1 LAST VALUE 42.2
J 2
(1050 3000);
DISPLAY 0.617021 (1050 3000);
PAINT SKYBLUE (1050 3000);
FORCEPROP 1 LAST TOLERANCE 1.0%
J 0
(1075 3000);
DISPLAY 0.617021 (1075 3000);
PAINT SKYBLUE (1075 3000);
FORCEPROP 1 LAST MATERIAL EMPTY
J 0
(1075 2950);
DISPLAY 0.617021 (1075 2950);
PAINT RED (1075 2950);
FORCEPROP 1 LAST PACK_TYPE 0402
J 0
(1325 2950);
DISPLAY 0.617021 (1325 2950);
PAINT SKYBLUE (1325 2950);
FORCEPROP 1 LAST LOCATION R6P9
J 0
(1025 3150);
DISPLAY 0.617021 (1025 3150);
PAINT AQUA (1025 3150);
FORCEPROP 1 LASTPIN (1175 3100) $PN 2
J 0
(1137 3112);
DISPLAY 0.617021 (1137 3112);
PAINT ORANGE (1137 3112);
FORCEPROP 1 LAST PART_NUMBER G21796-259
J 0
(1225 3100);
DISPLAY 0.617021 (1225 3100);
PAINT BLUE (1225 3100);
FORCEPROP 2 LAST CDS_LOCATION R6P9
J 0
(1025 3150);
DISPLAY 0.617021 (1025 3150);
PAINT AQUA (1025 3150);
DISPLAY INVISIBLE (1025 3150);
FORCEPROP 2 LAST CDS_LIB mstr_discrete
J 0
(1075 3100);
PAINT MONO (1075 3100);
DISPLAY INVISIBLE (1075 3100);
FORCEPROP 1 LAST PATH I155
J 0
(1025 3250);
DISPLAY 0.978723 (1025 3250);
PAINT WHITE (1025 3250);
DISPLAY INVISIBLE (1025 3250);
FORCEPROP 0 LAST ROOM DB1200Z
J 0
(1025 3300);
DISPLAY 1.021277 (1025 3300);
PAINT ORANGE (1025 3300);
DISPLAY INVISIBLE (1025 3300);
FORCEPROP 2 LAST SEC 1
J 0
(1025 3300);
DISPLAY 0.680851 (1025 3300);
PAINT MONO (1025 3300);
DISPLAY INVISIBLE (1025 3300);
FORCEPROP 2 LAST SEC_TYPE 0402
J 0
(1025 3300);
DISPLAY 1.021277 (1025 3300);
PAINT ORANGE (1025 3300);
DISPLAY INVISIBLE (1025 3300);
FORCEPROP 0 LAST BOM_COST SYS_CLOCK
J 0
(1025 3400);
DISPLAY 1.021277 (1025 3400);
PAINT ORANGE (1025 3400);
DISPLAY INVISIBLE (1025 3400);
FORCEADD GND..1
(1600 3000);
FORCEPROP 3 LASTPIN (1600 3050) SIG_NAME GND\g
J 0
(1610 3060);
DISPLAY 0.659574 (1610 3060);
PAINT MONO (1610 3060);
DISPLAY INVISIBLE (1610 3060);
FORCEPROP 1 LAST PATH I156
J 0
(1675 3000);
DISPLAY 0.872340 (1675 3000);
PAINT AQUA (1675 3000);
DISPLAY INVISIBLE (1675 3000);
FORCEPROP 2 LAST CDS_LIB mstr_symbols
J 0
(1600 3000);
PAINT MONO (1600 3000);
DISPLAY INVISIBLE (1600 3000);
FORCEPROP 1 LAST SIZE 1B
J 0
(1675 2950);
DISPLAY 0.872340 (1675 2950);
PAINT AQUA (1675 2950);
DISPLAY INVISIBLE (1675 2950);
FORCEPROP 1 LAST VOLTAGE 0.0V
J 0
(1555 2957);
DISPLAY 0.340426 (1555 2957);
PAINT SKYBLUE (1555 2957);
DISPLAY INVISIBLE (1555 2957);
FORCEPROP 1 LAST BODY_TYPE PLUMBING
J 0
(1555 2957);
DISPLAY 0.340426 (1555 2957);
PAINT GREEN (1555 2957);
DISPLAY INVISIBLE (1555 2957);
FORCEPROP 1 LAST HDL_POWER GND
J 0
(1600 3150);
DISPLAY 0.872340 (1600 3150);
PAINT GREEN (1600 3150);
DISPLAY INVISIBLE (1600 3150);
FORCEADD RES..1
(1050 2775);
FORCEPROP 1 LASTPIN (950 2775) $PN 1
J 0
(962 2787);
DISPLAY 0.617021 (962 2787);
PAINT ORANGE (962 2787);
FORCEPROP 1 LAST WATTAGE 1/16W
J 2
(1025 2625);
DISPLAY 0.617021 (1025 2625);
PAINT SKYBLUE (1025 2625);
FORCEPROP 1 LAST VALUE 42.2
J 2
(1025 2675);
DISPLAY 0.617021 (1025 2675);
PAINT SKYBLUE (1025 2675);
FORCEPROP 1 LAST LOCATION R6P13
J 0
(1000 2825);
DISPLAY 0.617021 (1000 2825);
PAINT AQUA (1000 2825);
FORCEPROP 1 LASTPIN (1150 2775) $PN 2
J 0
(1112 2787);
DISPLAY 0.617021 (1112 2787);
PAINT ORANGE (1112 2787);
FORCEPROP 1 LAST TOLERANCE 1.0%
J 0
(1050 2675);
DISPLAY 0.617021 (1050 2675);
PAINT SKYBLUE (1050 2675);
FORCEPROP 1 LAST MATERIAL EMPTY
J 0
(1050 2625);
DISPLAY 0.617021 (1050 2625);
PAINT RED (1050 2625);
FORCEPROP 1 LAST PART_NUMBER G21796-259
J 0
(1200 2775);
DISPLAY 0.617021 (1200 2775);
PAINT BLUE (1200 2775);
FORCEPROP 1 LAST PACK_TYPE 0402
J 0
(1300 2625);
DISPLAY 0.617021 (1300 2625);
PAINT SKYBLUE (1300 2625);
FORCEPROP 2 LAST SEC_TYPE 0402
J 0
(1000 2975);
DISPLAY 1.021277 (1000 2975);
PAINT ORANGE (1000 2975);
DISPLAY INVISIBLE (1000 2975);
FORCEPROP 2 LAST SEC 1
J 0
(1000 2975);
DISPLAY 0.680851 (1000 2975);
PAINT MONO (1000 2975);
DISPLAY INVISIBLE (1000 2975);
FORCEPROP 2 LAST CDS_LOCATION R6P13
J 0
(1000 2825);
DISPLAY 0.617021 (1000 2825);
PAINT AQUA (1000 2825);
DISPLAY INVISIBLE (1000 2825);
FORCEPROP 1 LAST PATH I157
J 0
(1000 2925);
DISPLAY 0.978723 (1000 2925);
PAINT WHITE (1000 2925);
DISPLAY INVISIBLE (1000 2925);
FORCEPROP 0 LAST ROOM DB1200Z
J 0
(1000 2975);
DISPLAY 1.021277 (1000 2975);
PAINT ORANGE (1000 2975);
DISPLAY INVISIBLE (1000 2975);
FORCEPROP 0 LAST BOM_COST SYS_CLOCK
J 0
(1000 3075);
DISPLAY 1.021277 (1000 3075);
PAINT ORANGE (1000 3075);
DISPLAY INVISIBLE (1000 3075);
FORCEPROP 2 LAST CDS_LIB mstr_discrete
J 0
(1050 2775);
PAINT MONO (1050 2775);
DISPLAY INVISIBLE (1050 2775);
FORCEADD GND..1
(1575 2675);
FORCEPROP 3 LASTPIN (1575 2725) SIG_NAME GND\g
J 0
(1585 2735);
DISPLAY 0.659574 (1585 2735);
PAINT MONO (1585 2735);
DISPLAY INVISIBLE (1585 2735);
FORCEPROP 1 LAST VOLTAGE 0.0V
J 0
(1530 2632);
DISPLAY 0.340426 (1530 2632);
PAINT SKYBLUE (1530 2632);
DISPLAY INVISIBLE (1530 2632);
FORCEPROP 1 LAST PATH I158
J 0
(1650 2675);
DISPLAY 0.872340 (1650 2675);
PAINT AQUA (1650 2675);
DISPLAY INVISIBLE (1650 2675);
FORCEPROP 1 LAST SIZE 1B
J 0
(1650 2625);
DISPLAY 0.872340 (1650 2625);
PAINT AQUA (1650 2625);
DISPLAY INVISIBLE (1650 2625);
FORCEPROP 2 LAST CDS_LIB mstr_symbols
J 0
(1575 2675);
PAINT MONO (1575 2675);
DISPLAY INVISIBLE (1575 2675);
FORCEPROP 1 LAST BODY_TYPE PLUMBING
J 0
(1530 2632);
DISPLAY 0.340426 (1530 2632);
PAINT GREEN (1530 2632);
DISPLAY INVISIBLE (1530 2632);
FORCEPROP 1 LAST HDL_POWER GND
J 0
(1575 2825);
DISPLAY 0.872340 (1575 2825);
PAINT GREEN (1575 2825);
DISPLAY INVISIBLE (1575 2825);
FORCEADD RES..1
(1050 2450);
FORCEPROP 1 LASTPIN (950 2450) $PN 1
J 0
(962 2462);
DISPLAY 0.617021 (962 2462);
PAINT ORANGE (962 2462);
FORCEPROP 1 LAST WATTAGE 1/16W
J 2
(1025 2300);
DISPLAY 0.617021 (1025 2300);
PAINT SKYBLUE (1025 2300);
FORCEPROP 1 LAST VALUE 42.2
J 2
(1025 2350);
DISPLAY 0.617021 (1025 2350);
PAINT SKYBLUE (1025 2350);
FORCEPROP 1 LAST LOCATION R6P12
J 0
(1000 2500);
DISPLAY 0.617021 (1000 2500);
PAINT AQUA (1000 2500);
FORCEPROP 1 LAST MATERIAL EMPTY
J 0
(1050 2300);
DISPLAY 0.617021 (1050 2300);
PAINT RED (1050 2300);
FORCEPROP 1 LASTPIN (1150 2450) $PN 2
J 0
(1112 2462);
DISPLAY 0.617021 (1112 2462);
PAINT ORANGE (1112 2462);
FORCEPROP 1 LAST TOLERANCE 1.0%
J 0
(1050 2350);
DISPLAY 0.617021 (1050 2350);
PAINT SKYBLUE (1050 2350);
FORCEPROP 1 LAST PART_NUMBER G21796-259
J 0
(1200 2450);
DISPLAY 0.617021 (1200 2450);
PAINT BLUE (1200 2450);
FORCEPROP 1 LAST PACK_TYPE 0402
J 0
(1300 2300);
DISPLAY 0.617021 (1300 2300);
PAINT SKYBLUE (1300 2300);
FORCEPROP 2 LAST CDS_LOCATION R6P12
J 0
(1000 2500);
DISPLAY 0.617021 (1000 2500);
PAINT AQUA (1000 2500);
DISPLAY INVISIBLE (1000 2500);
FORCEPROP 1 LAST PATH I159
J 0
(1000 2600);
DISPLAY 0.978723 (1000 2600);
PAINT WHITE (1000 2600);
DISPLAY INVISIBLE (1000 2600);
FORCEPROP 2 LAST SEC 1
J 0
(1000 2650);
DISPLAY 0.680851 (1000 2650);
PAINT MONO (1000 2650);
DISPLAY INVISIBLE (1000 2650);
FORCEPROP 0 LAST ROOM DB1200Z
J 0
(1000 2650);
DISPLAY 1.021277 (1000 2650);
PAINT ORANGE (1000 2650);
DISPLAY INVISIBLE (1000 2650);
FORCEPROP 2 LAST SEC_TYPE 0402
J 0
(1000 2650);
DISPLAY 1.021277 (1000 2650);
PAINT ORANGE (1000 2650);
DISPLAY INVISIBLE (1000 2650);
FORCEPROP 0 LAST BOM_COST SYS_CLOCK
J 0
(1000 2750);
DISPLAY 1.021277 (1000 2750);
PAINT ORANGE (1000 2750);
DISPLAY INVISIBLE (1000 2750);
FORCEPROP 2 LAST CDS_LIB mstr_discrete
J 0
(1050 2450);
PAINT MONO (1050 2450);
DISPLAY INVISIBLE (1050 2450);
FORCEADD OFFPAGE..2
(-2225 4175);
FORCEPROP 2 LAST $XR0 56 
J 0
(-2036 4175);
DISPLAY 0.638298 (-2036 4175);
PAINT MONO (-2036 4175);
FORCEPROP 2 LAST CDS_LIB mstr_standard
J 0
(-2225 4175);
PAINT ORANGE (-2225 4175);
DISPLAY INVISIBLE (-2225 4175);
FORCEPROP 2 LAST PATH I16
J 0
(-2050 4250);
DISPLAY 1.021277 (-2050 4250);
PAINT ORANGE (-2050 4250);
DISPLAY INVISIBLE (-2050 4250);
FORCEPROP 1 LAST OFFPAGE TRUE
J 0
(-1900 4050);
DISPLAY 0.872340 (-1900 4050);
PAINT GREEN (-1900 4050);
DISPLAY INVISIBLE (-1900 4050);
FORCEPROP 1 LAST COMMENT_BODY TRUE
J 0
(-2270 4080);
DISPLAY 0.872340 (-2270 4080);
PAINT GREEN (-2270 4080);
DISPLAY INVISIBLE (-2270 4080);
FORCEADD GND..1
(1575 2350);
FORCEPROP 3 LASTPIN (1575 2400) SIG_NAME GND\g
J 0
(1585 2410);
DISPLAY 0.659574 (1585 2410);
PAINT MONO (1585 2410);
DISPLAY INVISIBLE (1585 2410);
FORCEPROP 1 LAST VOLTAGE 0.0V
J 0
(1530 2307);
DISPLAY 0.340426 (1530 2307);
PAINT SKYBLUE (1530 2307);
DISPLAY INVISIBLE (1530 2307);
FORCEPROP 1 LAST SIZE 1B
J 0
(1650 2300);
DISPLAY 0.872340 (1650 2300);
PAINT AQUA (1650 2300);
DISPLAY INVISIBLE (1650 2300);
FORCEPROP 2 LAST CDS_LIB mstr_symbols
J 0
(1575 2350);
PAINT MONO (1575 2350);
DISPLAY INVISIBLE (1575 2350);
FORCEPROP 1 LAST PATH I160
J 0
(1650 2350);
DISPLAY 0.872340 (1650 2350);
PAINT AQUA (1650 2350);
DISPLAY INVISIBLE (1650 2350);
FORCEPROP 1 LAST BODY_TYPE PLUMBING
J 0
(1530 2307);
DISPLAY 0.340426 (1530 2307);
PAINT GREEN (1530 2307);
DISPLAY INVISIBLE (1530 2307);
FORCEPROP 1 LAST HDL_POWER GND
J 0
(1575 2500);
DISPLAY 0.872340 (1575 2500);
PAINT GREEN (1575 2500);
DISPLAY INVISIBLE (1575 2500);
FORCEADD RES..1
(1050 2125);
FORCEPROP 1 LAST WATTAGE 1/16W
J 2
(1025 1975);
DISPLAY 0.617021 (1025 1975);
PAINT SKYBLUE (1025 1975);
FORCEPROP 1 LAST MATERIAL EMPTY
J 0
(1050 1975);
DISPLAY 0.617021 (1050 1975);
PAINT RED (1050 1975);
FORCEPROP 1 LAST PACK_TYPE 0402
J 0
(1300 1975);
DISPLAY 0.617021 (1300 1975);
PAINT SKYBLUE (1300 1975);
FORCEPROP 1 LAST TOLERANCE 1.0%
J 0
(1050 2025);
DISPLAY 0.617021 (1050 2025);
PAINT SKYBLUE (1050 2025);
FORCEPROP 1 LAST VALUE 42.2
J 2
(1025 2025);
DISPLAY 0.617021 (1025 2025);
PAINT SKYBLUE (1025 2025);
FORCEPROP 1 LASTPIN (950 2125) $PN 1
J 0
(962 2137);
DISPLAY 0.617021 (962 2137);
PAINT ORANGE (962 2137);
FORCEPROP 1 LAST LOCATION R4D24
J 0
(1000 2175);
DISPLAY 0.617021 (1000 2175);
PAINT AQUA (1000 2175);
FORCEPROP 1 LASTPIN (1150 2125) $PN 2
J 0
(1112 2137);
DISPLAY 0.617021 (1112 2137);
PAINT ORANGE (1112 2137);
FORCEPROP 1 LAST PART_NUMBER G21796-259
J 0
(1200 2125);
DISPLAY 0.617021 (1200 2125);
PAINT BLUE (1200 2125);
FORCEPROP 2 LAST CDS_LOCATION R4D24
J 0
(1000 2175);
DISPLAY 0.617021 (1000 2175);
PAINT AQUA (1000 2175);
DISPLAY INVISIBLE (1000 2175);
FORCEPROP 1 LAST PATH I161
J 0
(1000 2275);
DISPLAY 0.978723 (1000 2275);
PAINT WHITE (1000 2275);
DISPLAY INVISIBLE (1000 2275);
FORCEPROP 0 LAST ROOM DB1200Z
J 0
(1000 2325);
DISPLAY 1.021277 (1000 2325);
PAINT ORANGE (1000 2325);
DISPLAY INVISIBLE (1000 2325);
FORCEPROP 2 LAST SEC 1
J 0
(1000 2325);
DISPLAY 0.680851 (1000 2325);
PAINT MONO (1000 2325);
DISPLAY INVISIBLE (1000 2325);
FORCEPROP 2 LAST SEC_TYPE 0402
J 0
(1000 2325);
DISPLAY 1.021277 (1000 2325);
PAINT ORANGE (1000 2325);
DISPLAY INVISIBLE (1000 2325);
FORCEPROP 0 LAST BOM_COST SYS_CLOCK
J 0
(1000 2425);
DISPLAY 1.021277 (1000 2425);
PAINT ORANGE (1000 2425);
DISPLAY INVISIBLE (1000 2425);
FORCEPROP 2 LAST CDS_LIB mstr_discrete
J 0
(1050 2125);
PAINT MONO (1050 2125);
DISPLAY INVISIBLE (1050 2125);
FORCEADD GND..1
(1575 2025);
FORCEPROP 3 LASTPIN (1575 2075) SIG_NAME GND\g
J 0
(1585 2085);
DISPLAY 0.659574 (1585 2085);
PAINT MONO (1585 2085);
DISPLAY INVISIBLE (1585 2085);
FORCEPROP 1 LAST VOLTAGE 0.0V
J 0
(1530 1982);
DISPLAY 0.340426 (1530 1982);
PAINT SKYBLUE (1530 1982);
DISPLAY INVISIBLE (1530 1982);
FORCEPROP 1 LAST SIZE 1B
J 0
(1650 1975);
DISPLAY 0.872340 (1650 1975);
PAINT AQUA (1650 1975);
DISPLAY INVISIBLE (1650 1975);
FORCEPROP 1 LAST PATH I162
J 0
(1650 2025);
DISPLAY 0.872340 (1650 2025);
PAINT AQUA (1650 2025);
DISPLAY INVISIBLE (1650 2025);
FORCEPROP 2 LAST CDS_LIB mstr_symbols
J 0
(1575 2025);
PAINT MONO (1575 2025);
DISPLAY INVISIBLE (1575 2025);
FORCEPROP 1 LAST BODY_TYPE PLUMBING
J 0
(1530 1982);
DISPLAY 0.340426 (1530 1982);
PAINT GREEN (1530 1982);
DISPLAY INVISIBLE (1530 1982);
FORCEPROP 1 LAST HDL_POWER GND
J 0
(1575 2175);
DISPLAY 0.872340 (1575 2175);
PAINT GREEN (1575 2175);
DISPLAY INVISIBLE (1575 2175);
FORCEADD RES..1
(1050 1800);
FORCEPROP 1 LASTPIN (950 1800) $PN 1
J 0
(962 1812);
DISPLAY 0.617021 (962 1812);
PAINT ORANGE (962 1812);
FORCEPROP 1 LAST WATTAGE 1/16W
J 2
(1025 1650);
DISPLAY 0.617021 (1025 1650);
PAINT SKYBLUE (1025 1650);
FORCEPROP 1 LAST VALUE 42.2
J 2
(1025 1700);
DISPLAY 0.617021 (1025 1700);
PAINT SKYBLUE (1025 1700);
FORCEPROP 1 LAST LOCATION R4D18
J 0
(1000 1850);
DISPLAY 0.617021 (1000 1850);
PAINT AQUA (1000 1850);
FORCEPROP 1 LAST TOLERANCE 1.0%
J 0
(1050 1700);
DISPLAY 0.617021 (1050 1700);
PAINT SKYBLUE (1050 1700);
FORCEPROP 1 LAST MATERIAL EMPTY
J 0
(1050 1650);
DISPLAY 0.617021 (1050 1650);
PAINT RED (1050 1650);
FORCEPROP 1 LASTPIN (1150 1800) $PN 2
J 0
(1112 1812);
DISPLAY 0.617021 (1112 1812);
PAINT ORANGE (1112 1812);
FORCEPROP 1 LAST PART_NUMBER G21796-259
J 0
(1200 1800);
DISPLAY 0.617021 (1200 1800);
PAINT BLUE (1200 1800);
FORCEPROP 1 LAST PACK_TYPE 0402
J 0
(1300 1650);
DISPLAY 0.617021 (1300 1650);
PAINT SKYBLUE (1300 1650);
FORCEPROP 2 LAST CDS_LOCATION R4D18
J 0
(1000 1850);
DISPLAY 0.617021 (1000 1850);
PAINT AQUA (1000 1850);
DISPLAY INVISIBLE (1000 1850);
FORCEPROP 0 LAST ROOM DB1200Z
J 0
(1000 2000);
DISPLAY 1.021277 (1000 2000);
PAINT ORANGE (1000 2000);
DISPLAY INVISIBLE (1000 2000);
FORCEPROP 1 LAST PATH I163
J 0
(1000 1950);
DISPLAY 0.978723 (1000 1950);
PAINT WHITE (1000 1950);
DISPLAY INVISIBLE (1000 1950);
FORCEPROP 2 LAST SEC_TYPE 0402
J 0
(1000 2000);
DISPLAY 1.021277 (1000 2000);
PAINT ORANGE (1000 2000);
DISPLAY INVISIBLE (1000 2000);
FORCEPROP 2 LAST SEC 1
J 0
(1000 2000);
DISPLAY 0.680851 (1000 2000);
PAINT MONO (1000 2000);
DISPLAY INVISIBLE (1000 2000);
FORCEPROP 2 LAST CDS_LIB mstr_discrete
J 0
(1050 1800);
PAINT MONO (1050 1800);
DISPLAY INVISIBLE (1050 1800);
FORCEPROP 0 LAST BOM_COST SYS_CLOCK
J 0
(1000 2100);
DISPLAY 1.021277 (1000 2100);
PAINT ORANGE (1000 2100);
DISPLAY INVISIBLE (1000 2100);
FORCEADD GND..1
(1575 1700);
FORCEPROP 3 LASTPIN (1575 1750) SIG_NAME GND\g
J 0
(1585 1760);
DISPLAY 0.659574 (1585 1760);
PAINT MONO (1585 1760);
DISPLAY INVISIBLE (1585 1760);
FORCEPROP 1 LAST VOLTAGE 0.0V
J 0
(1530 1657);
DISPLAY 0.340426 (1530 1657);
PAINT SKYBLUE (1530 1657);
DISPLAY INVISIBLE (1530 1657);
FORCEPROP 2 LAST CDS_LIB mstr_symbols
J 0
(1575 1700);
PAINT MONO (1575 1700);
DISPLAY INVISIBLE (1575 1700);
FORCEPROP 1 LAST SIZE 1B
J 0
(1650 1650);
DISPLAY 0.872340 (1650 1650);
PAINT AQUA (1650 1650);
DISPLAY INVISIBLE (1650 1650);
FORCEPROP 1 LAST PATH I164
J 0
(1650 1700);
DISPLAY 0.872340 (1650 1700);
PAINT AQUA (1650 1700);
DISPLAY INVISIBLE (1650 1700);
FORCEPROP 1 LAST BODY_TYPE PLUMBING
J 0
(1530 1657);
DISPLAY 0.340426 (1530 1657);
PAINT GREEN (1530 1657);
DISPLAY INVISIBLE (1530 1657);
FORCEPROP 1 LAST HDL_POWER GND
J 0
(1575 1850);
DISPLAY 0.872340 (1575 1850);
PAINT GREEN (1575 1850);
DISPLAY INVISIBLE (1575 1850);
FORCEADD RES..1
(1050 1475);
FORCEPROP 1 LASTPIN (950 1475) $PN 1
J 0
(962 1487);
DISPLAY 0.617021 (962 1487);
PAINT ORANGE (962 1487);
FORCEPROP 1 LAST WATTAGE 1/16W
J 2
(1025 1325);
DISPLAY 0.617021 (1025 1325);
PAINT SKYBLUE (1025 1325);
FORCEPROP 1 LAST VALUE 42.2
J 2
(1025 1375);
DISPLAY 0.617021 (1025 1375);
PAINT SKYBLUE (1025 1375);
FORCEPROP 1 LAST LOCATION R6P17
J 0
(1000 1525);
DISPLAY 0.617021 (1000 1525);
PAINT AQUA (1000 1525);
FORCEPROP 1 LASTPIN (1150 1475) $PN 2
J 0
(1112 1487);
DISPLAY 0.617021 (1112 1487);
PAINT ORANGE (1112 1487);
FORCEPROP 1 LAST TOLERANCE 1.0%
J 0
(1050 1375);
DISPLAY 0.617021 (1050 1375);
PAINT SKYBLUE (1050 1375);
FORCEPROP 1 LAST MATERIAL EMPTY
J 0
(1050 1325);
DISPLAY 0.617021 (1050 1325);
PAINT RED (1050 1325);
FORCEPROP 1 LAST PART_NUMBER G21796-259
J 0
(1200 1475);
DISPLAY 0.617021 (1200 1475);
PAINT BLUE (1200 1475);
FORCEPROP 1 LAST PACK_TYPE 0402
J 0
(1300 1325);
DISPLAY 0.617021 (1300 1325);
PAINT SKYBLUE (1300 1325);
FORCEPROP 2 LAST CDS_LOCATION R6P17
J 0
(1000 1525);
DISPLAY 0.617021 (1000 1525);
PAINT AQUA (1000 1525);
DISPLAY INVISIBLE (1000 1525);
FORCEPROP 1 LAST PATH I165
J 0
(1000 1625);
DISPLAY 0.978723 (1000 1625);
PAINT WHITE (1000 1625);
DISPLAY INVISIBLE (1000 1625);
FORCEPROP 0 LAST ROOM DB1200Z
J 0
(1000 1675);
DISPLAY 1.021277 (1000 1675);
PAINT ORANGE (1000 1675);
DISPLAY INVISIBLE (1000 1675);
FORCEPROP 2 LAST SEC 1
J 0
(1000 1675);
DISPLAY 0.680851 (1000 1675);
PAINT MONO (1000 1675);
DISPLAY INVISIBLE (1000 1675);
FORCEPROP 2 LAST SEC_TYPE 0402
J 0
(1000 1675);
DISPLAY 1.021277 (1000 1675);
PAINT ORANGE (1000 1675);
DISPLAY INVISIBLE (1000 1675);
FORCEPROP 0 LAST BOM_COST SYS_CLOCK
J 0
(1000 1775);
DISPLAY 1.021277 (1000 1775);
PAINT ORANGE (1000 1775);
DISPLAY INVISIBLE (1000 1775);
FORCEPROP 2 LAST CDS_LIB mstr_discrete
J 0
(1050 1475);
PAINT MONO (1050 1475);
DISPLAY INVISIBLE (1050 1475);
FORCEADD GND..1
(1575 1375);
FORCEPROP 3 LASTPIN (1575 1425) SIG_NAME GND\g
J 0
(1585 1435);
DISPLAY 0.659574 (1585 1435);
PAINT MONO (1585 1435);
DISPLAY INVISIBLE (1585 1435);
FORCEPROP 1 LAST VOLTAGE 0.0V
J 0
(1530 1332);
DISPLAY 0.340426 (1530 1332);
PAINT SKYBLUE (1530 1332);
DISPLAY INVISIBLE (1530 1332);
FORCEPROP 1 LAST PATH I166
J 0
(1650 1375);
DISPLAY 0.872340 (1650 1375);
PAINT AQUA (1650 1375);
DISPLAY INVISIBLE (1650 1375);
FORCEPROP 1 LAST SIZE 1B
J 0
(1650 1325);
DISPLAY 0.872340 (1650 1325);
PAINT AQUA (1650 1325);
DISPLAY INVISIBLE (1650 1325);
FORCEPROP 2 LAST CDS_LIB mstr_symbols
J 0
(1575 1375);
PAINT MONO (1575 1375);
DISPLAY INVISIBLE (1575 1375);
FORCEPROP 1 LAST BODY_TYPE PLUMBING
J 0
(1530 1332);
DISPLAY 0.340426 (1530 1332);
PAINT GREEN (1530 1332);
DISPLAY INVISIBLE (1530 1332);
FORCEPROP 1 LAST HDL_POWER GND
J 0
(1575 1525);
DISPLAY 0.872340 (1575 1525);
PAINT GREEN (1575 1525);
DISPLAY INVISIBLE (1575 1525);
FORCEADD RES..1
(1050 1150);
FORCEPROP 1 LASTPIN (950 1150) $PN 1
J 0
(962 1162);
DISPLAY 0.617021 (962 1162);
PAINT ORANGE (962 1162);
FORCEPROP 1 LAST WATTAGE 1/16W
J 2
(1025 1000);
DISPLAY 0.617021 (1025 1000);
PAINT SKYBLUE (1025 1000);
FORCEPROP 1 LAST VALUE 42.2
J 2
(1025 1050);
DISPLAY 0.617021 (1025 1050);
PAINT SKYBLUE (1025 1050);
FORCEPROP 1 LAST LOCATION R6P15
J 0
(1000 1200);
DISPLAY 0.617021 (1000 1200);
PAINT AQUA (1000 1200);
FORCEPROP 1 LAST PACK_TYPE 0402
J 0
(1300 1000);
DISPLAY 0.617021 (1300 1000);
PAINT SKYBLUE (1300 1000);
FORCEPROP 1 LAST MATERIAL EMPTY
J 0
(1050 1000);
DISPLAY 0.617021 (1050 1000);
PAINT RED (1050 1000);
FORCEPROP 1 LASTPIN (1150 1150) $PN 2
J 0
(1112 1162);
DISPLAY 0.617021 (1112 1162);
PAINT ORANGE (1112 1162);
FORCEPROP 1 LAST TOLERANCE 1.0%
J 0
(1050 1050);
DISPLAY 0.617021 (1050 1050);
PAINT SKYBLUE (1050 1050);
FORCEPROP 1 LAST PART_NUMBER G21796-259
J 0
(1200 1150);
DISPLAY 0.617021 (1200 1150);
PAINT BLUE (1200 1150);
FORCEPROP 2 LAST CDS_LOCATION R6P15
J 0
(1000 1200);
DISPLAY 0.617021 (1000 1200);
PAINT AQUA (1000 1200);
DISPLAY INVISIBLE (1000 1200);
FORCEPROP 0 LAST ROOM DB1200Z
J 0
(1000 1350);
DISPLAY 1.021277 (1000 1350);
PAINT ORANGE (1000 1350);
DISPLAY INVISIBLE (1000 1350);
FORCEPROP 1 LAST PATH I167
J 0
(1000 1300);
DISPLAY 0.978723 (1000 1300);
PAINT WHITE (1000 1300);
DISPLAY INVISIBLE (1000 1300);
FORCEPROP 2 LAST SEC 1
J 0
(1000 1350);
DISPLAY 0.680851 (1000 1350);
PAINT MONO (1000 1350);
DISPLAY INVISIBLE (1000 1350);
FORCEPROP 2 LAST SEC_TYPE 0402
J 0
(1000 1350);
DISPLAY 1.021277 (1000 1350);
PAINT ORANGE (1000 1350);
DISPLAY INVISIBLE (1000 1350);
FORCEPROP 0 LAST BOM_COST SYS_CLOCK
J 0
(1000 1450);
DISPLAY 1.021277 (1000 1450);
PAINT ORANGE (1000 1450);
DISPLAY INVISIBLE (1000 1450);
FORCEPROP 2 LAST CDS_LIB mstr_discrete
J 0
(1050 1150);
PAINT MONO (1050 1150);
DISPLAY INVISIBLE (1050 1150);
FORCEADD GND..1
(1575 1050);
FORCEPROP 3 LASTPIN (1575 1100) SIG_NAME GND\g
J 0
(1585 1110);
DISPLAY 0.659574 (1585 1110);
PAINT MONO (1585 1110);
DISPLAY INVISIBLE (1585 1110);
FORCEPROP 1 LAST VOLTAGE 0.0V
J 0
(1530 1007);
DISPLAY 0.340426 (1530 1007);
PAINT SKYBLUE (1530 1007);
DISPLAY INVISIBLE (1530 1007);
FORCEPROP 1 LAST SIZE 1B
J 0
(1650 1000);
DISPLAY 0.872340 (1650 1000);
PAINT AQUA (1650 1000);
DISPLAY INVISIBLE (1650 1000);
FORCEPROP 2 LAST CDS_LIB mstr_symbols
J 0
(1575 1050);
PAINT MONO (1575 1050);
DISPLAY INVISIBLE (1575 1050);
FORCEPROP 1 LAST PATH I168
J 0
(1650 1050);
DISPLAY 0.872340 (1650 1050);
PAINT AQUA (1650 1050);
DISPLAY INVISIBLE (1650 1050);
FORCEPROP 1 LAST BODY_TYPE PLUMBING
J 0
(1530 1007);
DISPLAY 0.340426 (1530 1007);
PAINT GREEN (1530 1007);
DISPLAY INVISIBLE (1530 1007);
FORCEPROP 1 LAST HDL_POWER GND
J 0
(1575 1200);
DISPLAY 0.872340 (1575 1200);
PAINT GREEN (1575 1200);
DISPLAY INVISIBLE (1575 1200);
FORCEADD GND..1
(-2775 4325);
FORCEPROP 3 LASTPIN (-2775 4375) SIG_NAME GND\g
J 0
(-2765 4385);
DISPLAY 0.659574 (-2765 4385);
PAINT MONO (-2765 4385);
DISPLAY INVISIBLE (-2765 4385);
FORCEPROP 1 LAST VOLTAGE 0.0V
J 0
(-2820 4282);
DISPLAY 0.340426 (-2820 4282);
PAINT SKYBLUE (-2820 4282);
DISPLAY INVISIBLE (-2820 4282);
FORCEPROP 1 LAST SIZE 1B
J 0
(-2700 4275);
DISPLAY 0.872340 (-2700 4275);
PAINT AQUA (-2700 4275);
DISPLAY INVISIBLE (-2700 4275);
FORCEPROP 1 LAST PATH I169
J 0
(-2700 4325);
DISPLAY 0.872340 (-2700 4325);
PAINT AQUA (-2700 4325);
DISPLAY INVISIBLE (-2700 4325);
FORCEPROP 2 LAST CDS_LIB mstr_symbols
J 0
(-2775 4325);
PAINT ORANGE (-2775 4325);
DISPLAY INVISIBLE (-2775 4325);
FORCEPROP 1 LAST BODY_TYPE PLUMBING
J 0
(-2820 4282);
DISPLAY 0.340426 (-2820 4282);
PAINT GREEN (-2820 4282);
DISPLAY INVISIBLE (-2820 4282);
FORCEPROP 1 LAST HDL_POWER GND
J 0
(-2775 4475);
DISPLAY 0.872340 (-2775 4475);
PAINT GREEN (-2775 4475);
DISPLAY INVISIBLE (-2775 4475);
FORCEADD GND..1
(-2800 4700);
FORCEPROP 3 LASTPIN (-2800 4750) SIG_NAME GND\g
J 0
(-2790 4760);
DISPLAY 0.659574 (-2790 4760);
PAINT MONO (-2790 4760);
DISPLAY INVISIBLE (-2790 4760);
FORCEPROP 1 LAST VOLTAGE 0.0V
J 0
(-2845 4657);
DISPLAY 0.340426 (-2845 4657);
PAINT SKYBLUE (-2845 4657);
DISPLAY INVISIBLE (-2845 4657);
FORCEPROP 1 LAST SIZE 1B
J 0
(-2725 4650);
DISPLAY 0.872340 (-2725 4650);
PAINT AQUA (-2725 4650);
DISPLAY INVISIBLE (-2725 4650);
FORCEPROP 2 LAST CDS_LIB mstr_symbols
J 0
(-2800 4700);
PAINT ORANGE (-2800 4700);
DISPLAY INVISIBLE (-2800 4700);
FORCEPROP 1 LAST PATH I170
J 0
(-2725 4700);
DISPLAY 0.872340 (-2725 4700);
PAINT AQUA (-2725 4700);
DISPLAY INVISIBLE (-2725 4700);
FORCEPROP 1 LAST BODY_TYPE PLUMBING
J 0
(-2845 4657);
DISPLAY 0.340426 (-2845 4657);
PAINT GREEN (-2845 4657);
DISPLAY INVISIBLE (-2845 4657);
FORCEPROP 1 LAST HDL_POWER GND
J 0
(-2800 4850);
DISPLAY 0.872340 (-2800 4850);
PAINT GREEN (-2800 4850);
DISPLAY INVISIBLE (-2800 4850);
FORCEADD RES..1
(-3925 4175);
FORCEPROP 1 LAST VALUE 27.4
J 2
(-4000 4125);
DISPLAY 0.617021 (-4000 4125);
PAINT SKYBLUE (-4000 4125);
FORCEPROP 1 LAST WATTAGE 1/16W
J 2
(-3950 4075);
DISPLAY 0.617021 (-3950 4075);
PAINT SKYBLUE (-3950 4075);
FORCEPROP 1 LAST PACK_TYPE 0402
J 0
(-3850 4075);
DISPLAY 0.617021 (-3850 4075);
PAINT SKYBLUE (-3850 4075);
FORCEPROP 1 LAST TOLERANCE 1%
J 0
(-3925 4075);
DISPLAY 0.617021 (-3925 4075);
PAINT SKYBLUE (-3925 4075);
FORCEPROP 1 LASTPIN (-4025 4175) $PN 1
J 0
(-4013 4187);
DISPLAY 0.617021 (-4013 4187);
PAINT ORANGE (-4013 4187);
FORCEPROP 1 LASTPIN (-3825 4175) $PN 2
J 0
(-3863 4187);
DISPLAY 0.617021 (-3863 4187);
PAINT ORANGE (-3863 4187);
FORCEPROP 1 LAST MATERIAL CHIP
J 0
(-3875 4125);
DISPLAY 0.617021 (-3875 4125);
PAINT SKYBLUE (-3875 4125);
FORCEPROP 1 LAST LOCATION R4D19
J 0
(-3975 4225);
DISPLAY 0.617021 (-3975 4225);
PAINT AQUA (-3975 4225);
FORCEPROP 1 LAST PART_NUMBER G21796-182
J 0
(-3800 4175);
DISPLAY 0.617021 (-3800 4175);
PAINT BLUE (-3800 4175);
FORCEPROP 2 LAST CDS_LOCATION R4D19
J 0
(-3975 4225);
DISPLAY 0.617021 (-3975 4225);
PAINT AQUA (-3975 4225);
DISPLAY INVISIBLE (-3975 4225);
FORCEPROP 2 LAST CDS_LIB mstr_discrete
J 0
(-3925 4175);
PAINT ORANGE (-3925 4175);
DISPLAY INVISIBLE (-3925 4175);
FORCEPROP 0 LAST ROOM DB1200Z
J 0
(-3975 4325);
DISPLAY 1.021277 (-3975 4325);
PAINT ORANGE (-3975 4325);
DISPLAY INVISIBLE (-3975 4325);
FORCEPROP 1 LAST PATH I19
J 0
(-3975 4325);
DISPLAY 0.978723 (-3975 4325);
PAINT WHITE (-3975 4325);
DISPLAY INVISIBLE (-3975 4325);
FORCEPROP 0 LAST BOM_COST SYS_CLOCK
J 0
(-3975 4425);
DISPLAY 1.021277 (-3975 4425);
PAINT ORANGE (-3975 4425);
DISPLAY INVISIBLE (-3975 4425);
FORCEPROP 2 LAST SEC_TYPE 0402
J 0
(-3975 4375);
DISPLAY 1.021277 (-3975 4375);
PAINT ORANGE (-3975 4375);
DISPLAY INVISIBLE (-3975 4375);
FORCEPROP 2 LAST SEC 1
J 0
(-3975 4375);
DISPLAY 0.680851 (-3975 4375);
PAINT MONO (-3975 4375);
DISPLAY INVISIBLE (-3975 4375);
FORCEADD OFFPAGE..1
(-4900 4175);
FORCEPROP 2 LAST $XR0 102 
J 0
(-5152 4175);
DISPLAY 0.638298 (-5152 4175);
PAINT MONO (-5152 4175);
FORCEPROP 2 LAST CDS_LIB mstr_standard
J 0
(-4900 4175);
PAINT ORANGE (-4900 4175);
DISPLAY INVISIBLE (-4900 4175);
FORCEPROP 2 LAST PATH I20
J 0
(-4850 4250);
DISPLAY 1.021277 (-4850 4250);
PAINT ORANGE (-4850 4250);
DISPLAY INVISIBLE (-4850 4250);
FORCEPROP 1 LAST OFFPAGE TRUE
J 0
(-4575 4050);
DISPLAY 0.872340 (-4575 4050);
PAINT GREEN (-4575 4050);
DISPLAY INVISIBLE (-4575 4050);
FORCEPROP 1 LAST COMMENT_BODY TRUE
J 0
(-4775 4075);
DISPLAY 0.872340 (-4775 4075);
PAINT GREEN (-4775 4075);
DISPLAY INVISIBLE (-4775 4075);
FORCEADD OFFPAGE..2
(-2225 3850);
FORCEPROP 2 LAST $XR0 56 
J 0
(-2036 3850);
DISPLAY 0.638298 (-2036 3850);
PAINT MONO (-2036 3850);
FORCEPROP 2 LAST PATH I21
J 0
(-2050 3925);
DISPLAY 1.021277 (-2050 3925);
PAINT ORANGE (-2050 3925);
DISPLAY INVISIBLE (-2050 3925);
FORCEPROP 2 LAST CDS_LIB mstr_standard
J 0
(-2225 3850);
PAINT ORANGE (-2225 3850);
DISPLAY INVISIBLE (-2225 3850);
FORCEPROP 1 LAST OFFPAGE TRUE
J 0
(-1900 3725);
DISPLAY 0.872340 (-1900 3725);
PAINT GREEN (-1900 3725);
DISPLAY INVISIBLE (-1900 3725);
FORCEPROP 1 LAST COMMENT_BODY TRUE
J 0
(-2270 3755);
DISPLAY 0.872340 (-2270 3755);
PAINT GREEN (-2270 3755);
DISPLAY INVISIBLE (-2270 3755);
FORCEADD RES..1
(-3925 3850);
FORCEPROP 1 LAST VALUE 27.4
J 2
(-4000 3800);
DISPLAY 0.617021 (-4000 3800);
PAINT SKYBLUE (-4000 3800);
FORCEPROP 1 LAST WATTAGE 1/16W
J 2
(-3950 3750);
DISPLAY 0.617021 (-3950 3750);
PAINT SKYBLUE (-3950 3750);
FORCEPROP 1 LAST TOLERANCE 1%
J 0
(-3925 3750);
DISPLAY 0.617021 (-3925 3750);
PAINT SKYBLUE (-3925 3750);
FORCEPROP 1 LASTPIN (-4025 3850) $PN 1
J 0
(-4013 3862);
DISPLAY 0.617021 (-4013 3862);
PAINT ORANGE (-4013 3862);
FORCEPROP 1 LASTPIN (-3825 3850) $PN 2
J 0
(-3863 3862);
DISPLAY 0.617021 (-3863 3862);
PAINT ORANGE (-3863 3862);
FORCEPROP 1 LAST MATERIAL CHIP
J 0
(-3875 3800);
DISPLAY 0.617021 (-3875 3800);
PAINT SKYBLUE (-3875 3800);
FORCEPROP 1 LAST PACK_TYPE 0402
J 0
(-3850 3750);
DISPLAY 0.617021 (-3850 3750);
PAINT SKYBLUE (-3850 3750);
FORCEPROP 1 LAST LOCATION R4D21
J 0
(-3975 3900);
DISPLAY 0.617021 (-3975 3900);
PAINT AQUA (-3975 3900);
FORCEPROP 1 LAST PART_NUMBER G21796-182
J 0
(-3800 3850);
DISPLAY 0.617021 (-3800 3850);
PAINT BLUE (-3800 3850);
FORCEPROP 0 LAST ROOM DB1200Z
J 0
(-3975 4000);
DISPLAY 1.021277 (-3975 4000);
PAINT ORANGE (-3975 4000);
DISPLAY INVISIBLE (-3975 4000);
FORCEPROP 1 LAST PATH I24
J 0
(-3975 4000);
DISPLAY 0.978723 (-3975 4000);
PAINT WHITE (-3975 4000);
DISPLAY INVISIBLE (-3975 4000);
FORCEPROP 2 LAST CDS_LOCATION R4D21
J 0
(-3975 3900);
DISPLAY 0.617021 (-3975 3900);
PAINT AQUA (-3975 3900);
DISPLAY INVISIBLE (-3975 3900);
FORCEPROP 2 LAST SEC 1
J 0
(-3975 4050);
DISPLAY 0.680851 (-3975 4050);
PAINT MONO (-3975 4050);
DISPLAY INVISIBLE (-3975 4050);
FORCEPROP 2 LAST SEC_TYPE 0402
J 0
(-3975 4050);
DISPLAY 1.021277 (-3975 4050);
PAINT ORANGE (-3975 4050);
DISPLAY INVISIBLE (-3975 4050);
FORCEPROP 2 LAST CDS_LIB mstr_discrete
J 0
(-3925 3850);
PAINT ORANGE (-3925 3850);
DISPLAY INVISIBLE (-3925 3850);
FORCEPROP 0 LAST BOM_COST SYS_CLOCK
J 0
(-3975 4100);
DISPLAY 1.021277 (-3975 4100);
PAINT ORANGE (-3975 4100);
DISPLAY INVISIBLE (-3975 4100);
FORCEADD OFFPAGE..1
(-4900 3850);
FORCEPROP 2 LAST $XR0 102 
J 0
(-5152 3850);
DISPLAY 0.638298 (-5152 3850);
PAINT MONO (-5152 3850);
FORCEPROP 2 LAST CDS_LIB mstr_standard
J 0
(-4900 3850);
PAINT ORANGE (-4900 3850);
DISPLAY INVISIBLE (-4900 3850);
FORCEPROP 2 LAST PATH I25
J 0
(-4850 3925);
DISPLAY 1.021277 (-4850 3925);
PAINT ORANGE (-4850 3925);
DISPLAY INVISIBLE (-4850 3925);
FORCEPROP 1 LAST OFFPAGE TRUE
J 0
(-4575 3725);
DISPLAY 0.872340 (-4575 3725);
PAINT GREEN (-4575 3725);
DISPLAY INVISIBLE (-4575 3725);
FORCEPROP 1 LAST COMMENT_BODY TRUE
J 0
(-4775 3750);
DISPLAY 0.872340 (-4775 3750);
PAINT GREEN (-4775 3750);
DISPLAY INVISIBLE (-4775 3750);
FORCEADD OFFPAGE..2
(-2225 3525);
FORCEPROP 2 LAST $XR0 63 
J 0
(-2036 3525);
DISPLAY 0.638298 (-2036 3525);
PAINT MONO (-2036 3525);
FORCEPROP 2 LAST CDS_LIB mstr_standard
J 0
(-2225 3525);
PAINT ORANGE (-2225 3525);
DISPLAY INVISIBLE (-2225 3525);
FORCEPROP 2 LAST PATH I26
J 0
(-2050 3600);
DISPLAY 1.021277 (-2050 3600);
PAINT ORANGE (-2050 3600);
DISPLAY INVISIBLE (-2050 3600);
FORCEPROP 1 LAST OFFPAGE TRUE
J 0
(-1900 3400);
DISPLAY 0.872340 (-1900 3400);
PAINT GREEN (-1900 3400);
DISPLAY INVISIBLE (-1900 3400);
FORCEPROP 1 LAST COMMENT_BODY TRUE
J 0
(-2270 3430);
DISPLAY 0.872340 (-2270 3430);
PAINT GREEN (-2270 3430);
DISPLAY INVISIBLE (-2270 3430);
FORCEADD RES..1
(-3925 3525);
FORCEPROP 1 LAST VALUE 27.4
J 2
(-4000 3475);
DISPLAY 0.617021 (-4000 3475);
PAINT SKYBLUE (-4000 3475);
FORCEPROP 1 LASTPIN (-4025 3525) $PN 1
J 0
(-4013 3537);
DISPLAY 0.617021 (-4013 3537);
PAINT ORANGE (-4013 3537);
FORCEPROP 1 LAST WATTAGE 1/16W
J 2
(-3950 3425);
DISPLAY 0.617021 (-3950 3425);
PAINT SKYBLUE (-3950 3425);
FORCEPROP 1 LAST TOLERANCE 1%
J 0
(-3925 3425);
DISPLAY 0.617021 (-3925 3425);
PAINT SKYBLUE (-3925 3425);
FORCEPROP 1 LASTPIN (-3825 3525) $PN 2
J 0
(-3863 3537);
DISPLAY 0.617021 (-3863 3537);
PAINT ORANGE (-3863 3537);
FORCEPROP 1 LAST MATERIAL CHIP
J 0
(-3875 3475);
DISPLAY 0.617021 (-3875 3475);
PAINT SKYBLUE (-3875 3475);
FORCEPROP 1 LAST PACK_TYPE 0402
J 0
(-3850 3425);
DISPLAY 0.617021 (-3850 3425);
PAINT SKYBLUE (-3850 3425);
FORCEPROP 1 LAST LOCATION R4D13
J 0
(-3975 3575);
DISPLAY 0.617021 (-3975 3575);
PAINT AQUA (-3975 3575);
FORCEPROP 1 LAST PART_NUMBER G21796-182
J 0
(-3800 3525);
DISPLAY 0.617021 (-3800 3525);
PAINT BLUE (-3800 3525);
FORCEPROP 2 LAST CDS_LIB mstr_discrete
J 0
(-3925 3525);
PAINT ORANGE (-3925 3525);
DISPLAY INVISIBLE (-3925 3525);
FORCEPROP 2 LAST CDS_LOCATION R4D13
J 0
(-3975 3575);
DISPLAY 0.617021 (-3975 3575);
PAINT AQUA (-3975 3575);
DISPLAY INVISIBLE (-3975 3575);
FORCEPROP 0 LAST ROOM DB1200Z
J 0
(-3975 3675);
DISPLAY 1.021277 (-3975 3675);
PAINT ORANGE (-3975 3675);
DISPLAY INVISIBLE (-3975 3675);
FORCEPROP 1 LAST PATH I29
J 0
(-3975 3675);
DISPLAY 0.978723 (-3975 3675);
PAINT WHITE (-3975 3675);
DISPLAY INVISIBLE (-3975 3675);
FORCEPROP 2 LAST SEC 1
J 0
(-3975 3725);
DISPLAY 0.680851 (-3975 3725);
PAINT MONO (-3975 3725);
DISPLAY INVISIBLE (-3975 3725);
FORCEPROP 2 LAST SEC_TYPE 0402
J 0
(-3975 3725);
DISPLAY 1.021277 (-3975 3725);
PAINT ORANGE (-3975 3725);
DISPLAY INVISIBLE (-3975 3725);
FORCEPROP 0 LAST BOM_COST SYS_CLOCK
J 0
(-3975 3775);
DISPLAY 1.021277 (-3975 3775);
PAINT ORANGE (-3975 3775);
DISPLAY INVISIBLE (-3975 3775);
FORCEADD OFFPAGE..1
(-4900 3525);
FORCEPROP 2 LAST $XR0 102 
J 0
(-5152 3525);
DISPLAY 0.638298 (-5152 3525);
PAINT MONO (-5152 3525);
FORCEPROP 2 LAST CDS_LIB mstr_standard
J 0
(-4900 3525);
PAINT ORANGE (-4900 3525);
DISPLAY INVISIBLE (-4900 3525);
FORCEPROP 2 LAST PATH I30
J 0
(-4850 3600);
DISPLAY 1.021277 (-4850 3600);
PAINT ORANGE (-4850 3600);
DISPLAY INVISIBLE (-4850 3600);
FORCEPROP 1 LAST OFFPAGE TRUE
J 0
(-4575 3400);
DISPLAY 0.872340 (-4575 3400);
PAINT GREEN (-4575 3400);
DISPLAY INVISIBLE (-4575 3400);
FORCEPROP 1 LAST COMMENT_BODY TRUE
J 0
(-4775 3425);
DISPLAY 0.872340 (-4775 3425);
PAINT GREEN (-4775 3425);
DISPLAY INVISIBLE (-4775 3425);
FORCEADD OFFPAGE..2
(-2225 3200);
FORCEPROP 2 LAST $XR0 63 
J 0
(-2036 3200);
DISPLAY 0.638298 (-2036 3200);
PAINT MONO (-2036 3200);
FORCEPROP 2 LAST CDS_LIB mstr_standard
J 0
(-2225 3200);
PAINT ORANGE (-2225 3200);
DISPLAY INVISIBLE (-2225 3200);
FORCEPROP 2 LAST PATH I31
J 0
(-2050 3275);
DISPLAY 1.021277 (-2050 3275);
PAINT ORANGE (-2050 3275);
DISPLAY INVISIBLE (-2050 3275);
FORCEPROP 1 LAST OFFPAGE TRUE
J 0
(-1900 3075);
DISPLAY 0.872340 (-1900 3075);
PAINT GREEN (-1900 3075);
DISPLAY INVISIBLE (-1900 3075);
FORCEPROP 1 LAST COMMENT_BODY TRUE
J 0
(-2270 3105);
DISPLAY 0.872340 (-2270 3105);
PAINT GREEN (-2270 3105);
DISPLAY INVISIBLE (-2270 3105);
FORCEADD RES..1
(-3925 3200);
FORCEPROP 1 LAST VALUE 27.4
J 2
(-4000 3150);
DISPLAY 0.617021 (-4000 3150);
PAINT SKYBLUE (-4000 3150);
FORCEPROP 1 LASTPIN (-4025 3200) $PN 1
J 0
(-4013 3212);
DISPLAY 0.617021 (-4013 3212);
PAINT ORANGE (-4013 3212);
FORCEPROP 1 LAST WATTAGE 1/16W
J 2
(-3950 3100);
DISPLAY 0.617021 (-3950 3100);
PAINT SKYBLUE (-3950 3100);
FORCEPROP 1 LAST TOLERANCE 1%
J 0
(-3925 3100);
DISPLAY 0.617021 (-3925 3100);
PAINT SKYBLUE (-3925 3100);
FORCEPROP 1 LASTPIN (-3825 3200) $PN 2
J 0
(-3863 3212);
DISPLAY 0.617021 (-3863 3212);
PAINT ORANGE (-3863 3212);
FORCEPROP 1 LAST MATERIAL CHIP
J 0
(-3875 3150);
DISPLAY 0.617021 (-3875 3150);
PAINT SKYBLUE (-3875 3150);
FORCEPROP 1 LAST PACK_TYPE 0402
J 0
(-3850 3100);
DISPLAY 0.617021 (-3850 3100);
PAINT SKYBLUE (-3850 3100);
FORCEPROP 1 LAST LOCATION R4D16
J 0
(-3975 3250);
DISPLAY 0.617021 (-3975 3250);
PAINT AQUA (-3975 3250);
FORCEPROP 1 LAST PART_NUMBER G21796-182
J 0
(-3800 3200);
DISPLAY 0.617021 (-3800 3200);
PAINT BLUE (-3800 3200);
FORCEPROP 2 LAST CDS_LOCATION R4D16
J 0
(-3975 3250);
DISPLAY 0.617021 (-3975 3250);
PAINT AQUA (-3975 3250);
DISPLAY INVISIBLE (-3975 3250);
FORCEPROP 2 LAST CDS_LIB mstr_discrete
J 0
(-3925 3200);
PAINT ORANGE (-3925 3200);
DISPLAY INVISIBLE (-3925 3200);
FORCEPROP 2 LAST SEC_TYPE 0402
J 0
(-3975 3400);
DISPLAY 1.021277 (-3975 3400);
PAINT ORANGE (-3975 3400);
DISPLAY INVISIBLE (-3975 3400);
FORCEPROP 0 LAST BOM_COST SYS_CLOCK
J 0
(-3975 3450);
DISPLAY 1.021277 (-3975 3450);
PAINT ORANGE (-3975 3450);
DISPLAY INVISIBLE (-3975 3450);
FORCEPROP 2 LAST SEC 1
J 0
(-3975 3400);
DISPLAY 0.680851 (-3975 3400);
PAINT MONO (-3975 3400);
DISPLAY INVISIBLE (-3975 3400);
FORCEPROP 1 LAST PATH I34
J 0
(-3975 3350);
DISPLAY 0.978723 (-3975 3350);
PAINT WHITE (-3975 3350);
DISPLAY INVISIBLE (-3975 3350);
FORCEPROP 0 LAST ROOM DB1200Z
J 0
(-3975 3350);
DISPLAY 1.021277 (-3975 3350);
PAINT ORANGE (-3975 3350);
DISPLAY INVISIBLE (-3975 3350);
FORCEADD OFFPAGE..1
(-4900 3200);
FORCEPROP 2 LAST $XR0 102 
J 0
(-5152 3200);
DISPLAY 0.638298 (-5152 3200);
PAINT MONO (-5152 3200);
FORCEPROP 2 LAST CDS_LIB mstr_standard
J 0
(-4900 3200);
PAINT ORANGE (-4900 3200);
DISPLAY INVISIBLE (-4900 3200);
FORCEPROP 2 LAST PATH I35
J 0
(-4850 3275);
DISPLAY 1.021277 (-4850 3275);
PAINT ORANGE (-4850 3275);
DISPLAY INVISIBLE (-4850 3275);
FORCEPROP 1 LAST OFFPAGE TRUE
J 0
(-4575 3075);
DISPLAY 0.872340 (-4575 3075);
PAINT GREEN (-4575 3075);
DISPLAY INVISIBLE (-4575 3075);
FORCEPROP 1 LAST COMMENT_BODY TRUE
J 0
(-4775 3100);
DISPLAY 0.872340 (-4775 3100);
PAINT GREEN (-4775 3100);
DISPLAY INVISIBLE (-4775 3100);
FORCEADD OFFPAGE..2
(-2225 2875);
FORCEPROP 2 LAST $XR0 55 
J 0
(-2036 2875);
DISPLAY 0.638298 (-2036 2875);
PAINT MONO (-2036 2875);
FORCEPROP 2 LAST CDS_LIB mstr_standard
J 0
(-2225 2875);
PAINT ORANGE (-2225 2875);
DISPLAY INVISIBLE (-2225 2875);
FORCEPROP 2 LAST PATH I36
J 0
(-2050 2950);
DISPLAY 1.021277 (-2050 2950);
PAINT ORANGE (-2050 2950);
DISPLAY INVISIBLE (-2050 2950);
FORCEPROP 1 LAST OFFPAGE TRUE
J 0
(-1900 2750);
DISPLAY 0.872340 (-1900 2750);
PAINT GREEN (-1900 2750);
DISPLAY INVISIBLE (-1900 2750);
FORCEPROP 1 LAST COMMENT_BODY TRUE
J 0
(-2270 2780);
DISPLAY 0.872340 (-2270 2780);
PAINT GREEN (-2270 2780);
DISPLAY INVISIBLE (-2270 2780);
FORCEADD RES..1
(-3925 2875);
FORCEPROP 1 LAST VALUE 27.4
J 2
(-4000 2825);
DISPLAY 0.617021 (-4000 2825);
PAINT SKYBLUE (-4000 2825);
FORCEPROP 1 LAST WATTAGE 1/16W
J 2
(-3950 2775);
DISPLAY 0.617021 (-3950 2775);
PAINT SKYBLUE (-3950 2775);
FORCEPROP 1 LAST TOLERANCE 1%
J 0
(-3925 2775);
DISPLAY 0.617021 (-3925 2775);
PAINT SKYBLUE (-3925 2775);
FORCEPROP 1 LASTPIN (-4025 2875) $PN 1
J 0
(-4013 2887);
DISPLAY 0.617021 (-4013 2887);
PAINT ORANGE (-4013 2887);
FORCEPROP 1 LAST LOCATION R4D9
J 0
(-3975 2925);
DISPLAY 0.617021 (-3975 2925);
PAINT AQUA (-3975 2925);
FORCEPROP 1 LASTPIN (-3825 2875) $PN 2
J 0
(-3863 2887);
DISPLAY 0.617021 (-3863 2887);
PAINT ORANGE (-3863 2887);
FORCEPROP 1 LAST MATERIAL CHIP
J 0
(-3875 2825);
DISPLAY 0.617021 (-3875 2825);
PAINT SKYBLUE (-3875 2825);
FORCEPROP 1 LAST PACK_TYPE 0402
J 0
(-3850 2775);
DISPLAY 0.617021 (-3850 2775);
PAINT SKYBLUE (-3850 2775);
FORCEPROP 1 LAST PART_NUMBER G21796-182
J 0
(-3800 2875);
DISPLAY 0.617021 (-3800 2875);
PAINT BLUE (-3800 2875);
FORCEPROP 2 LAST CDS_LOCATION R4D9
J 0
(-3975 2925);
DISPLAY 0.617021 (-3975 2925);
PAINT AQUA (-3975 2925);
DISPLAY INVISIBLE (-3975 2925);
FORCEPROP 1 LAST PATH I39
J 0
(-3975 3025);
DISPLAY 0.978723 (-3975 3025);
PAINT WHITE (-3975 3025);
DISPLAY INVISIBLE (-3975 3025);
FORCEPROP 0 LAST ROOM DB1200Z
J 0
(-3975 3025);
DISPLAY 1.021277 (-3975 3025);
PAINT ORANGE (-3975 3025);
DISPLAY INVISIBLE (-3975 3025);
FORCEPROP 2 LAST CDS_LIB mstr_discrete
J 0
(-3925 2875);
PAINT ORANGE (-3925 2875);
DISPLAY INVISIBLE (-3925 2875);
FORCEPROP 2 LAST SEC_TYPE 0402
J 0
(-3975 3075);
DISPLAY 1.021277 (-3975 3075);
PAINT ORANGE (-3975 3075);
DISPLAY INVISIBLE (-3975 3075);
FORCEPROP 0 LAST BOM_COST SYS_CLOCK
J 0
(-3975 3125);
DISPLAY 1.021277 (-3975 3125);
PAINT ORANGE (-3975 3125);
DISPLAY INVISIBLE (-3975 3125);
FORCEPROP 2 LAST SEC 1
J 0
(-3975 3075);
DISPLAY 0.680851 (-3975 3075);
PAINT MONO (-3975 3075);
DISPLAY INVISIBLE (-3975 3075);
FORCEADD OFFPAGE..1
(-675 1250);
FORCEPROP 2 LAST $XR0 102 
J 0
(-927 1250);
DISPLAY 0.638298 (-927 1250);
PAINT MONO (-927 1250);
FORCEPROP 2 LAST PATH I4
J 0
(-625 1325);
DISPLAY 1.021277 (-625 1325);
PAINT ORANGE (-625 1325);
DISPLAY INVISIBLE (-625 1325);
FORCEPROP 2 LAST CDS_LIB mstr_standard
J 0
(-675 1250);
PAINT ORANGE (-675 1250);
DISPLAY INVISIBLE (-675 1250);
FORCEPROP 1 LAST OFFPAGE TRUE
J 0
(-350 1125);
DISPLAY 0.872340 (-350 1125);
PAINT GREEN (-350 1125);
DISPLAY INVISIBLE (-350 1125);
FORCEPROP 1 LAST COMMENT_BODY TRUE
J 0
(-550 1150);
DISPLAY 0.872340 (-550 1150);
PAINT GREEN (-550 1150);
DISPLAY INVISIBLE (-550 1150);
FORCEADD OFFPAGE..1
(-4900 2875);
FORCEPROP 2 LAST $XR0 102 
J 0
(-5152 2875);
DISPLAY 0.638298 (-5152 2875);
PAINT MONO (-5152 2875);
FORCEPROP 2 LAST CDS_LIB mstr_standard
J 0
(-4900 2875);
PAINT ORANGE (-4900 2875);
DISPLAY INVISIBLE (-4900 2875);
FORCEPROP 2 LAST PATH I40
J 0
(-4850 2950);
DISPLAY 1.021277 (-4850 2950);
PAINT ORANGE (-4850 2950);
DISPLAY INVISIBLE (-4850 2950);
FORCEPROP 1 LAST OFFPAGE TRUE
J 0
(-4575 2750);
DISPLAY 0.872340 (-4575 2750);
PAINT GREEN (-4575 2750);
DISPLAY INVISIBLE (-4575 2750);
FORCEPROP 1 LAST COMMENT_BODY TRUE
J 0
(-4775 2775);
DISPLAY 0.872340 (-4775 2775);
PAINT GREEN (-4775 2775);
DISPLAY INVISIBLE (-4775 2775);
FORCEADD OFFPAGE..2
(-2225 2550);
FORCEPROP 2 LAST $XR0 55 
J 0
(-2036 2550);
DISPLAY 0.638298 (-2036 2550);
PAINT MONO (-2036 2550);
FORCEPROP 2 LAST CDS_LIB mstr_standard
J 0
(-2225 2550);
PAINT ORANGE (-2225 2550);
DISPLAY INVISIBLE (-2225 2550);
FORCEPROP 2 LAST PATH I41
J 0
(-2050 2625);
DISPLAY 1.021277 (-2050 2625);
PAINT ORANGE (-2050 2625);
DISPLAY INVISIBLE (-2050 2625);
FORCEPROP 1 LAST OFFPAGE TRUE
J 0
(-1900 2425);
DISPLAY 0.872340 (-1900 2425);
PAINT GREEN (-1900 2425);
DISPLAY INVISIBLE (-1900 2425);
FORCEPROP 1 LAST COMMENT_BODY TRUE
J 0
(-2270 2455);
DISPLAY 0.872340 (-2270 2455);
PAINT GREEN (-2270 2455);
DISPLAY INVISIBLE (-2270 2455);
FORCEADD RES..1
(-3925 2550);
FORCEPROP 1 LAST VALUE 27.4
J 2
(-4000 2500);
DISPLAY 0.617021 (-4000 2500);
PAINT SKYBLUE (-4000 2500);
FORCEPROP 1 LAST WATTAGE 1/16W
J 2
(-3950 2450);
DISPLAY 0.617021 (-3950 2450);
PAINT SKYBLUE (-3950 2450);
FORCEPROP 1 LAST TOLERANCE 1%
J 0
(-3925 2450);
DISPLAY 0.617021 (-3925 2450);
PAINT SKYBLUE (-3925 2450);
FORCEPROP 1 LAST MATERIAL CHIP
J 0
(-3875 2500);
DISPLAY 0.617021 (-3875 2500);
PAINT SKYBLUE (-3875 2500);
FORCEPROP 1 LAST PACK_TYPE 0402
J 0
(-3850 2450);
DISPLAY 0.617021 (-3850 2450);
PAINT SKYBLUE (-3850 2450);
FORCEPROP 1 LASTPIN (-4025 2550) $PN 1
J 0
(-4013 2562);
DISPLAY 0.617021 (-4013 2562);
PAINT ORANGE (-4013 2562);
FORCEPROP 1 LASTPIN (-3825 2550) $PN 2
J 0
(-3863 2562);
DISPLAY 0.617021 (-3863 2562);
PAINT ORANGE (-3863 2562);
FORCEPROP 1 LAST LOCATION R4D11
J 0
(-3975 2600);
DISPLAY 0.617021 (-3975 2600);
PAINT AQUA (-3975 2600);
FORCEPROP 1 LAST PART_NUMBER G21796-182
J 0
(-3800 2550);
DISPLAY 0.617021 (-3800 2550);
PAINT BLUE (-3800 2550);
FORCEPROP 2 LAST CDS_LIB mstr_discrete
J 0
(-3925 2550);
PAINT ORANGE (-3925 2550);
DISPLAY INVISIBLE (-3925 2550);
FORCEPROP 2 LAST SEC 1
J 0
(-3975 2750);
DISPLAY 0.680851 (-3975 2750);
PAINT MONO (-3975 2750);
DISPLAY INVISIBLE (-3975 2750);
FORCEPROP 0 LAST ROOM DB1200Z
J 0
(-3975 2700);
DISPLAY 1.021277 (-3975 2700);
PAINT ORANGE (-3975 2700);
DISPLAY INVISIBLE (-3975 2700);
FORCEPROP 1 LAST PATH I44
J 0
(-3975 2700);
DISPLAY 0.978723 (-3975 2700);
PAINT WHITE (-3975 2700);
DISPLAY INVISIBLE (-3975 2700);
FORCEPROP 2 LAST CDS_LOCATION R4D11
J 0
(-3975 2600);
DISPLAY 0.617021 (-3975 2600);
PAINT AQUA (-3975 2600);
DISPLAY INVISIBLE (-3975 2600);
FORCEPROP 2 LAST SEC_TYPE 0402
J 0
(-3975 2750);
DISPLAY 1.021277 (-3975 2750);
PAINT ORANGE (-3975 2750);
DISPLAY INVISIBLE (-3975 2750);
FORCEPROP 0 LAST BOM_COST SYS_CLOCK
J 0
(-3975 2800);
DISPLAY 1.021277 (-3975 2800);
PAINT ORANGE (-3975 2800);
DISPLAY INVISIBLE (-3975 2800);
FORCEADD OFFPAGE..1
(-4900 2550);
FORCEPROP 2 LAST $XR0 102 
J 0
(-5152 2550);
DISPLAY 0.638298 (-5152 2550);
PAINT MONO (-5152 2550);
FORCEPROP 2 LAST CDS_LIB mstr_standard
J 0
(-4900 2550);
PAINT ORANGE (-4900 2550);
DISPLAY INVISIBLE (-4900 2550);
FORCEPROP 2 LAST PATH I45
J 0
(-4850 2625);
DISPLAY 1.021277 (-4850 2625);
PAINT ORANGE (-4850 2625);
DISPLAY INVISIBLE (-4850 2625);
FORCEPROP 1 LAST OFFPAGE TRUE
J 0
(-4575 2425);
DISPLAY 0.872340 (-4575 2425);
PAINT GREEN (-4575 2425);
DISPLAY INVISIBLE (-4575 2425);
FORCEPROP 1 LAST COMMENT_BODY TRUE
J 0
(-4775 2450);
DISPLAY 0.872340 (-4775 2450);
PAINT GREEN (-4775 2450);
DISPLAY INVISIBLE (-4775 2450);
FORCEADD OFFPAGE..2
(-2225 2225);
FORCEPROP 2 LAST $XR0 55 
J 0
(-2036 2225);
DISPLAY 0.638298 (-2036 2225);
PAINT MONO (-2036 2225);
FORCEPROP 2 LAST CDS_LIB mstr_standard
J 0
(-2225 2225);
PAINT ORANGE (-2225 2225);
DISPLAY INVISIBLE (-2225 2225);
FORCEPROP 2 LAST PATH I46
J 0
(-2050 2300);
DISPLAY 1.021277 (-2050 2300);
PAINT ORANGE (-2050 2300);
DISPLAY INVISIBLE (-2050 2300);
FORCEPROP 1 LAST OFFPAGE TRUE
J 0
(-1900 2100);
DISPLAY 0.872340 (-1900 2100);
PAINT GREEN (-1900 2100);
DISPLAY INVISIBLE (-1900 2100);
FORCEPROP 1 LAST COMMENT_BODY TRUE
J 0
(-2270 2130);
DISPLAY 0.872340 (-2270 2130);
PAINT GREEN (-2270 2130);
DISPLAY INVISIBLE (-2270 2130);
FORCEADD RES..1
(-3925 2225);
FORCEPROP 1 LAST VALUE 27.4
J 2
(-4000 2175);
DISPLAY 0.617021 (-4000 2175);
PAINT SKYBLUE (-4000 2175);
FORCEPROP 1 LASTPIN (-4025 2225) $PN 1
J 0
(-4013 2237);
DISPLAY 0.617021 (-4013 2237);
PAINT ORANGE (-4013 2237);
FORCEPROP 1 LAST WATTAGE 1/16W
J 2
(-3950 2125);
DISPLAY 0.617021 (-3950 2125);
PAINT SKYBLUE (-3950 2125);
FORCEPROP 1 LAST LOCATION R4D2
J 0
(-3975 2275);
DISPLAY 0.617021 (-3975 2275);
PAINT AQUA (-3975 2275);
FORCEPROP 1 LAST TOLERANCE 1%
J 0
(-3925 2125);
DISPLAY 0.617021 (-3925 2125);
PAINT SKYBLUE (-3925 2125);
FORCEPROP 1 LASTPIN (-3825 2225) $PN 2
J 0
(-3863 2237);
DISPLAY 0.617021 (-3863 2237);
PAINT ORANGE (-3863 2237);
FORCEPROP 1 LAST MATERIAL CHIP
J 0
(-3875 2175);
DISPLAY 0.617021 (-3875 2175);
PAINT SKYBLUE (-3875 2175);
FORCEPROP 1 LAST PACK_TYPE 0402
J 0
(-3850 2125);
DISPLAY 0.617021 (-3850 2125);
PAINT SKYBLUE (-3850 2125);
FORCEPROP 1 LAST PART_NUMBER G21796-182
J 0
(-3800 2225);
DISPLAY 0.617021 (-3800 2225);
PAINT BLUE (-3800 2225);
FORCEPROP 2 LAST CDS_LOCATION R4D2
J 0
(-3975 2275);
DISPLAY 0.617021 (-3975 2275);
PAINT AQUA (-3975 2275);
DISPLAY INVISIBLE (-3975 2275);
FORCEPROP 2 LAST CDS_LIB mstr_discrete
J 0
(-3925 2225);
PAINT ORANGE (-3925 2225);
DISPLAY INVISIBLE (-3925 2225);
FORCEPROP 0 LAST ROOM DB1200Z
J 0
(-3975 2375);
DISPLAY 1.021277 (-3975 2375);
PAINT ORANGE (-3975 2375);
DISPLAY INVISIBLE (-3975 2375);
FORCEPROP 1 LAST PATH I49
J 0
(-3975 2375);
DISPLAY 0.978723 (-3975 2375);
PAINT WHITE (-3975 2375);
DISPLAY INVISIBLE (-3975 2375);
FORCEPROP 2 LAST $SEC 1
J 0
(-3975 2425);
PAINT MONO (-3975 2425);
DISPLAY INVISIBLE (-3975 2425);
FORCEPROP 2 LAST CDS_SEC 1
J 0
(-3975 2425);
PAINT MONO (-3975 2425);
DISPLAY INVISIBLE (-3975 2425);
FORCEPROP 0 LAST BOM_COST SYS_CLOCK
J 0
(-3975 2475);
DISPLAY 1.021277 (-3975 2475);
PAINT ORANGE (-3975 2475);
DISPLAY INVISIBLE (-3975 2475);
FORCEADD OFFPAGE..2
(1950 1250);
FORCEPROP 2 LAST $XR0 21 
J 0
(2139 1250);
DISPLAY 0.638298 (2139 1250);
PAINT MONO (2139 1250);
FORCEPROP 2 LAST CDS_LIB mstr_standard
J 0
(1950 1250);
PAINT ORANGE (1950 1250);
DISPLAY INVISIBLE (1950 1250);
FORCEPROP 2 LAST PATH I5
J 0
(2125 1325);
DISPLAY 1.021277 (2125 1325);
PAINT ORANGE (2125 1325);
DISPLAY INVISIBLE (2125 1325);
FORCEPROP 1 LAST OFFPAGE TRUE
J 0
(2275 1125);
DISPLAY 0.872340 (2275 1125);
PAINT GREEN (2275 1125);
DISPLAY INVISIBLE (2275 1125);
FORCEPROP 1 LAST COMMENT_BODY TRUE
J 0
(1905 1155);
DISPLAY 0.872340 (1905 1155);
PAINT GREEN (1905 1155);
DISPLAY INVISIBLE (1905 1155);
FORCEADD OFFPAGE..1
(-4900 2225);
FORCEPROP 2 LAST $XR0 102 
J 0
(-5152 2225);
DISPLAY 0.638298 (-5152 2225);
PAINT MONO (-5152 2225);
FORCEPROP 2 LAST CDS_LIB mstr_standard
J 0
(-4900 2225);
PAINT ORANGE (-4900 2225);
DISPLAY INVISIBLE (-4900 2225);
FORCEPROP 2 LAST PATH I50
J 0
(-4850 2300);
DISPLAY 1.021277 (-4850 2300);
PAINT ORANGE (-4850 2300);
DISPLAY INVISIBLE (-4850 2300);
FORCEPROP 1 LAST OFFPAGE TRUE
J 0
(-4575 2100);
DISPLAY 0.872340 (-4575 2100);
PAINT GREEN (-4575 2100);
DISPLAY INVISIBLE (-4575 2100);
FORCEPROP 1 LAST COMMENT_BODY TRUE
J 0
(-4775 2125);
DISPLAY 0.872340 (-4775 2125);
PAINT GREEN (-4775 2125);
DISPLAY INVISIBLE (-4775 2125);
FORCEADD OFFPAGE..2
(-2225 1900);
FORCEPROP 2 LAST $XR0 55 
J 0
(-2036 1900);
DISPLAY 0.638298 (-2036 1900);
PAINT MONO (-2036 1900);
FORCEPROP 2 LAST CDS_LIB mstr_standard
J 0
(-2225 1900);
PAINT ORANGE (-2225 1900);
DISPLAY INVISIBLE (-2225 1900);
FORCEPROP 2 LAST PATH I51
J 0
(-2050 1975);
DISPLAY 1.021277 (-2050 1975);
PAINT ORANGE (-2050 1975);
DISPLAY INVISIBLE (-2050 1975);
FORCEPROP 1 LAST OFFPAGE TRUE
J 0
(-1900 1775);
DISPLAY 0.872340 (-1900 1775);
PAINT GREEN (-1900 1775);
DISPLAY INVISIBLE (-1900 1775);
FORCEPROP 1 LAST COMMENT_BODY TRUE
J 0
(-2270 1805);
DISPLAY 0.872340 (-2270 1805);
PAINT GREEN (-2270 1805);
DISPLAY INVISIBLE (-2270 1805);
FORCEADD RES..1
(-3925 1900);
FORCEPROP 1 LAST VALUE 27.4
J 2
(-4000 1850);
DISPLAY 0.617021 (-4000 1850);
PAINT SKYBLUE (-4000 1850);
FORCEPROP 1 LASTPIN (-4025 1900) $PN 1
J 0
(-4013 1912);
DISPLAY 0.617021 (-4013 1912);
PAINT ORANGE (-4013 1912);
FORCEPROP 1 LAST LOCATION R4D1
J 0
(-3975 1950);
DISPLAY 0.617021 (-3975 1950);
PAINT AQUA (-3975 1950);
FORCEPROP 1 LAST WATTAGE 1/16W
J 2
(-3950 1800);
DISPLAY 0.617021 (-3950 1800);
PAINT SKYBLUE (-3950 1800);
FORCEPROP 1 LAST TOLERANCE 1%
J 0
(-3925 1800);
DISPLAY 0.617021 (-3925 1800);
PAINT SKYBLUE (-3925 1800);
FORCEPROP 1 LASTPIN (-3825 1900) $PN 2
J 0
(-3863 1912);
DISPLAY 0.617021 (-3863 1912);
PAINT ORANGE (-3863 1912);
FORCEPROP 1 LAST MATERIAL CHIP
J 0
(-3875 1850);
DISPLAY 0.617021 (-3875 1850);
PAINT SKYBLUE (-3875 1850);
FORCEPROP 1 LAST PACK_TYPE 0402
J 0
(-3850 1800);
DISPLAY 0.617021 (-3850 1800);
PAINT SKYBLUE (-3850 1800);
FORCEPROP 1 LAST PART_NUMBER G21796-182
J 0
(-3800 1900);
DISPLAY 0.617021 (-3800 1900);
PAINT BLUE (-3800 1900);
FORCEPROP 2 LAST CDS_LOCATION R4D1
J 0
(-3975 1950);
DISPLAY 0.617021 (-3975 1950);
PAINT AQUA (-3975 1950);
DISPLAY INVISIBLE (-3975 1950);
FORCEPROP 2 LAST CDS_LIB mstr_discrete
J 0
(-3925 1900);
PAINT ORANGE (-3925 1900);
DISPLAY INVISIBLE (-3925 1900);
FORCEPROP 2 LAST SEC_TYPE 0402
J 0
(-3975 2100);
DISPLAY 1.021277 (-3975 2100);
PAINT ORANGE (-3975 2100);
DISPLAY INVISIBLE (-3975 2100);
FORCEPROP 0 LAST BOM_COST SYS_CLOCK
J 0
(-3975 2150);
DISPLAY 1.021277 (-3975 2150);
PAINT ORANGE (-3975 2150);
DISPLAY INVISIBLE (-3975 2150);
FORCEPROP 0 LAST ROOM DB1200Z
J 0
(-3975 2050);
DISPLAY 1.021277 (-3975 2050);
PAINT ORANGE (-3975 2050);
DISPLAY INVISIBLE (-3975 2050);
FORCEPROP 1 LAST PATH I54
J 0
(-3975 2050);
DISPLAY 0.978723 (-3975 2050);
PAINT WHITE (-3975 2050);
DISPLAY INVISIBLE (-3975 2050);
FORCEPROP 2 LAST SEC 1
J 0
(-3975 2100);
DISPLAY 0.680851 (-3975 2100);
PAINT MONO (-3975 2100);
DISPLAY INVISIBLE (-3975 2100);
FORCEADD OFFPAGE..1
(-4900 1900);
FORCEPROP 2 LAST $XR0 102 
J 0
(-5152 1900);
DISPLAY 0.638298 (-5152 1900);
PAINT MONO (-5152 1900);
FORCEPROP 2 LAST CDS_LIB mstr_standard
J 0
(-4900 1900);
PAINT ORANGE (-4900 1900);
DISPLAY INVISIBLE (-4900 1900);
FORCEPROP 2 LAST PATH I55
J 0
(-4850 1975);
DISPLAY 1.021277 (-4850 1975);
PAINT ORANGE (-4850 1975);
DISPLAY INVISIBLE (-4850 1975);
FORCEPROP 1 LAST OFFPAGE TRUE
J 0
(-4575 1775);
DISPLAY 0.872340 (-4575 1775);
PAINT GREEN (-4575 1775);
DISPLAY INVISIBLE (-4575 1775);
FORCEPROP 1 LAST COMMENT_BODY TRUE
J 0
(-4775 1800);
DISPLAY 0.872340 (-4775 1800);
PAINT GREEN (-4775 1800);
DISPLAY INVISIBLE (-4775 1800);
FORCEADD OFFPAGE..2
(-2225 1575);
FORCEPROP 2 LAST $XR0 55 
J 0
(-2036 1575);
DISPLAY 0.638298 (-2036 1575);
PAINT MONO (-2036 1575);
FORCEPROP 2 LAST CDS_LIB mstr_standard
J 0
(-2225 1575);
PAINT ORANGE (-2225 1575);
DISPLAY INVISIBLE (-2225 1575);
FORCEPROP 2 LAST PATH I56
J 0
(-2050 1650);
DISPLAY 1.021277 (-2050 1650);
PAINT ORANGE (-2050 1650);
DISPLAY INVISIBLE (-2050 1650);
FORCEPROP 1 LAST OFFPAGE TRUE
J 0
(-1900 1450);
DISPLAY 0.872340 (-1900 1450);
PAINT GREEN (-1900 1450);
DISPLAY INVISIBLE (-1900 1450);
FORCEPROP 1 LAST COMMENT_BODY TRUE
J 0
(-2270 1480);
DISPLAY 0.872340 (-2270 1480);
PAINT GREEN (-2270 1480);
DISPLAY INVISIBLE (-2270 1480);
FORCEADD RES..1
(-3925 1575);
FORCEPROP 1 LAST VALUE 27.4
J 2
(-4000 1525);
DISPLAY 0.617021 (-4000 1525);
PAINT SKYBLUE (-4000 1525);
FORCEPROP 1 LAST WATTAGE 1/16W
J 2
(-3950 1475);
DISPLAY 0.617021 (-3950 1475);
PAINT SKYBLUE (-3950 1475);
FORCEPROP 1 LAST TOLERANCE 1%
J 0
(-3925 1475);
DISPLAY 0.617021 (-3925 1475);
PAINT SKYBLUE (-3925 1475);
FORCEPROP 1 LAST PACK_TYPE 0402
J 0
(-3850 1475);
DISPLAY 0.617021 (-3850 1475);
PAINT SKYBLUE (-3850 1475);
FORCEPROP 1 LAST MATERIAL CHIP
J 0
(-3875 1525);
DISPLAY 0.617021 (-3875 1525);
PAINT SKYBLUE (-3875 1525);
FORCEPROP 1 LASTPIN (-4025 1575) $PN 1
J 0
(-4013 1587);
DISPLAY 0.617021 (-4013 1587);
PAINT ORANGE (-4013 1587);
FORCEPROP 1 LAST LOCATION R4D4
J 0
(-3975 1625);
DISPLAY 0.617021 (-3975 1625);
PAINT AQUA (-3975 1625);
FORCEPROP 1 LASTPIN (-3825 1575) $PN 2
J 0
(-3863 1587);
DISPLAY 0.617021 (-3863 1587);
PAINT ORANGE (-3863 1587);
FORCEPROP 1 LAST PART_NUMBER G21796-182
J 0
(-3800 1575);
DISPLAY 0.617021 (-3800 1575);
PAINT BLUE (-3800 1575);
FORCEPROP 2 LAST CDS_LOCATION R4D4
J 0
(-3975 1625);
DISPLAY 0.617021 (-3975 1625);
PAINT AQUA (-3975 1625);
DISPLAY INVISIBLE (-3975 1625);
FORCEPROP 1 LAST PATH I59
J 0
(-3975 1725);
DISPLAY 0.978723 (-3975 1725);
PAINT WHITE (-3975 1725);
DISPLAY INVISIBLE (-3975 1725);
FORCEPROP 0 LAST ROOM DB1200Z
J 0
(-3975 1725);
DISPLAY 1.021277 (-3975 1725);
PAINT ORANGE (-3975 1725);
DISPLAY INVISIBLE (-3975 1725);
FORCEPROP 2 LAST CDS_LIB mstr_discrete
J 0
(-3925 1575);
PAINT ORANGE (-3925 1575);
DISPLAY INVISIBLE (-3925 1575);
FORCEPROP 2 LAST SEC 1
J 0
(-3975 1775);
DISPLAY 0.680851 (-3975 1775);
PAINT MONO (-3975 1775);
DISPLAY INVISIBLE (-3975 1775);
FORCEPROP 2 LAST SEC_TYPE 0402
J 0
(-3975 1775);
DISPLAY 1.021277 (-3975 1775);
PAINT ORANGE (-3975 1775);
DISPLAY INVISIBLE (-3975 1775);
FORCEPROP 0 LAST BOM_COST SYS_CLOCK
J 0
(-3975 1825);
DISPLAY 1.021277 (-3975 1825);
PAINT ORANGE (-3975 1825);
DISPLAY INVISIBLE (-3975 1825);
FORCEADD OFFPAGE..2
(-2225 4900);
FORCEPROP 2 LAST $XR0 70 
J 0
(-2036 4900);
DISPLAY 0.638298 (-2036 4900);
PAINT MONO (-2036 4900);
FORCEPROP 2 LAST CDS_LIB mstr_standard
J 0
(-2225 4900);
PAINT ORANGE (-2225 4900);
DISPLAY INVISIBLE (-2225 4900);
FORCEPROP 2 LAST PATH I6
J 0
(-2050 4975);
DISPLAY 1.021277 (-2050 4975);
PAINT ORANGE (-2050 4975);
DISPLAY INVISIBLE (-2050 4975);
FORCEPROP 1 LAST OFFPAGE TRUE
J 0
(-1900 4775);
DISPLAY 0.872340 (-1900 4775);
PAINT GREEN (-1900 4775);
DISPLAY INVISIBLE (-1900 4775);
FORCEPROP 1 LAST COMMENT_BODY TRUE
J 0
(-2270 4805);
DISPLAY 0.872340 (-2270 4805);
PAINT GREEN (-2270 4805);
DISPLAY INVISIBLE (-2270 4805);
FORCEADD OFFPAGE..1
(-4900 1575);
FORCEPROP 2 LAST $XR0 102 
J 0
(-5152 1575);
DISPLAY 0.638298 (-5152 1575);
PAINT MONO (-5152 1575);
FORCEPROP 2 LAST CDS_LIB mstr_standard
J 0
(-4900 1575);
PAINT ORANGE (-4900 1575);
DISPLAY INVISIBLE (-4900 1575);
FORCEPROP 2 LAST PATH I60
J 0
(-4850 1650);
DISPLAY 1.021277 (-4850 1650);
PAINT ORANGE (-4850 1650);
DISPLAY INVISIBLE (-4850 1650);
FORCEPROP 1 LAST OFFPAGE TRUE
J 0
(-4575 1450);
DISPLAY 0.872340 (-4575 1450);
PAINT GREEN (-4575 1450);
DISPLAY INVISIBLE (-4575 1450);
FORCEPROP 1 LAST COMMENT_BODY TRUE
J 0
(-4775 1475);
DISPLAY 0.872340 (-4775 1475);
PAINT GREEN (-4775 1475);
DISPLAY INVISIBLE (-4775 1475);
FORCEADD OFFPAGE..2
(-2225 1250);
FORCEPROP 2 LAST $XR0 55 
J 0
(-2036 1250);
DISPLAY 0.638298 (-2036 1250);
PAINT MONO (-2036 1250);
FORCEPROP 2 LAST CDS_LIB mstr_standard
J 0
(-2225 1250);
PAINT ORANGE (-2225 1250);
DISPLAY INVISIBLE (-2225 1250);
FORCEPROP 2 LAST PATH I61
J 0
(-2050 1325);
DISPLAY 1.021277 (-2050 1325);
PAINT ORANGE (-2050 1325);
DISPLAY INVISIBLE (-2050 1325);
FORCEPROP 1 LAST OFFPAGE TRUE
J 0
(-1900 1125);
DISPLAY 0.872340 (-1900 1125);
PAINT GREEN (-1900 1125);
DISPLAY INVISIBLE (-1900 1125);
FORCEPROP 1 LAST COMMENT_BODY TRUE
J 0
(-2270 1155);
DISPLAY 0.872340 (-2270 1155);
PAINT GREEN (-2270 1155);
DISPLAY INVISIBLE (-2270 1155);
FORCEADD RES..1
(-3925 1250);
FORCEPROP 1 LAST VALUE 27.4
J 2
(-4000 1200);
DISPLAY 0.617021 (-4000 1200);
PAINT SKYBLUE (-4000 1200);
FORCEPROP 1 LAST WATTAGE 1/16W
J 2
(-3950 1150);
DISPLAY 0.617021 (-3950 1150);
PAINT SKYBLUE (-3950 1150);
FORCEPROP 1 LAST TOLERANCE 1%
J 0
(-3925 1150);
DISPLAY 0.617021 (-3925 1150);
PAINT SKYBLUE (-3925 1150);
FORCEPROP 1 LASTPIN (-4025 1250) $PN 1
J 0
(-4013 1262);
DISPLAY 0.617021 (-4013 1262);
PAINT ORANGE (-4013 1262);
FORCEPROP 1 LAST LOCATION R4D3
J 0
(-3975 1300);
DISPLAY 0.617021 (-3975 1300);
PAINT AQUA (-3975 1300);
FORCEPROP 1 LASTPIN (-3825 1250) $PN 2
J 0
(-3863 1262);
DISPLAY 0.617021 (-3863 1262);
PAINT ORANGE (-3863 1262);
FORCEPROP 1 LAST PACK_TYPE 0402
J 0
(-3850 1150);
DISPLAY 0.617021 (-3850 1150);
PAINT SKYBLUE (-3850 1150);
FORCEPROP 1 LAST MATERIAL CHIP
J 0
(-3875 1200);
DISPLAY 0.617021 (-3875 1200);
PAINT SKYBLUE (-3875 1200);
FORCEPROP 1 LAST PART_NUMBER G21796-182
J 0
(-3800 1250);
DISPLAY 0.617021 (-3800 1250);
PAINT BLUE (-3800 1250);
FORCEPROP 2 LAST CDS_LIB mstr_discrete
J 0
(-3925 1250);
PAINT ORANGE (-3925 1250);
DISPLAY INVISIBLE (-3925 1250);
FORCEPROP 0 LAST ROOM DB1200Z
J 0
(-3975 1400);
DISPLAY 1.021277 (-3975 1400);
PAINT ORANGE (-3975 1400);
DISPLAY INVISIBLE (-3975 1400);
FORCEPROP 1 LAST PATH I64
J 0
(-3975 1400);
DISPLAY 0.978723 (-3975 1400);
PAINT WHITE (-3975 1400);
DISPLAY INVISIBLE (-3975 1400);
FORCEPROP 2 LAST CDS_LOCATION R4D3
J 0
(-3975 1300);
DISPLAY 0.617021 (-3975 1300);
PAINT AQUA (-3975 1300);
DISPLAY INVISIBLE (-3975 1300);
FORCEPROP 2 LAST SEC 1
J 0
(-3975 1450);
DISPLAY 0.680851 (-3975 1450);
PAINT MONO (-3975 1450);
DISPLAY INVISIBLE (-3975 1450);
FORCEPROP 2 LAST SEC_TYPE 0402
J 0
(-3975 1450);
DISPLAY 1.021277 (-3975 1450);
PAINT ORANGE (-3975 1450);
DISPLAY INVISIBLE (-3975 1450);
FORCEPROP 0 LAST BOM_COST SYS_CLOCK
J 0
(-3975 1500);
DISPLAY 1.021277 (-3975 1500);
PAINT ORANGE (-3975 1500);
DISPLAY INVISIBLE (-3975 1500);
FORCEADD OFFPAGE..1
(-4900 1250);
FORCEPROP 2 LAST $XR0 102 
J 0
(-5152 1250);
DISPLAY 0.638298 (-5152 1250);
PAINT MONO (-5152 1250);
FORCEPROP 2 LAST CDS_LIB mstr_standard
J 0
(-4900 1250);
PAINT ORANGE (-4900 1250);
DISPLAY INVISIBLE (-4900 1250);
FORCEPROP 2 LAST PATH I65
J 0
(-4850 1325);
DISPLAY 1.021277 (-4850 1325);
PAINT ORANGE (-4850 1325);
DISPLAY INVISIBLE (-4850 1325);
FORCEPROP 1 LAST OFFPAGE TRUE
J 0
(-4575 1125);
DISPLAY 0.872340 (-4575 1125);
PAINT GREEN (-4575 1125);
DISPLAY INVISIBLE (-4575 1125);
FORCEPROP 1 LAST COMMENT_BODY TRUE
J 0
(-4775 1150);
DISPLAY 0.872340 (-4775 1150);
PAINT GREEN (-4775 1150);
DISPLAY INVISIBLE (-4775 1150);
FORCEADD OFFPAGE..2
(1950 1575);
FORCEPROP 2 LAST $XR0 21 
J 0
(2139 1575);
DISPLAY 0.638298 (2139 1575);
PAINT MONO (2139 1575);
FORCEPROP 2 LAST CDS_LIB mstr_standard
J 0
(1950 1575);
PAINT ORANGE (1950 1575);
DISPLAY INVISIBLE (1950 1575);
FORCEPROP 2 LAST PATH I66
J 0
(2125 1650);
DISPLAY 1.021277 (2125 1650);
PAINT ORANGE (2125 1650);
DISPLAY INVISIBLE (2125 1650);
FORCEPROP 1 LAST OFFPAGE TRUE
J 0
(2275 1450);
DISPLAY 0.872340 (2275 1450);
PAINT GREEN (2275 1450);
DISPLAY INVISIBLE (2275 1450);
FORCEPROP 1 LAST COMMENT_BODY TRUE
J 0
(1905 1480);
DISPLAY 0.872340 (1905 1480);
PAINT GREEN (1905 1480);
DISPLAY INVISIBLE (1905 1480);
FORCEADD RES..1
(300 1575);
FORCEPROP 1 LAST WATTAGE 1/16W
J 2
(275 1475);
DISPLAY 0.617021 (275 1475);
PAINT SKYBLUE (275 1475);
FORCEPROP 1 LAST PACK_TYPE 0402
J 0
(375 1475);
DISPLAY 0.617021 (375 1475);
PAINT SKYBLUE (375 1475);
FORCEPROP 1 LAST TOLERANCE 1%
J 0
(300 1475);
DISPLAY 0.617021 (300 1475);
PAINT SKYBLUE (300 1475);
FORCEPROP 1 LAST MATERIAL CHIP
J 0
(350 1525);
DISPLAY 0.617021 (350 1525);
PAINT SKYBLUE (350 1525);
FORCEPROP 1 LAST VALUE 27.4
J 2
(225 1525);
DISPLAY 0.617021 (225 1525);
PAINT SKYBLUE (225 1525);
FORCEPROP 1 LASTPIN (200 1575) $PN 1
J 0
(212 1587);
DISPLAY 0.617021 (212 1587);
PAINT ORANGE (212 1587);
FORCEPROP 1 LAST LOCATION R4D29
J 0
(250 1625);
DISPLAY 0.617021 (250 1625);
PAINT AQUA (250 1625);
FORCEPROP 1 LASTPIN (400 1575) $PN 2
J 0
(362 1587);
DISPLAY 0.617021 (362 1587);
PAINT ORANGE (362 1587);
FORCEPROP 1 LAST PART_NUMBER G21796-182
J 0
(425 1575);
DISPLAY 0.617021 (425 1575);
PAINT BLUE (425 1575);
FORCEPROP 0 LAST ROOM DB1200Z
J 0
(250 1725);
DISPLAY 1.021277 (250 1725);
PAINT ORANGE (250 1725);
DISPLAY INVISIBLE (250 1725);
FORCEPROP 1 LAST PATH I69
J 0
(250 1725);
DISPLAY 0.978723 (250 1725);
PAINT WHITE (250 1725);
DISPLAY INVISIBLE (250 1725);
FORCEPROP 2 LAST CDS_LOCATION R4D29
J 0
(250 1625);
DISPLAY 0.617021 (250 1625);
PAINT AQUA (250 1625);
DISPLAY INVISIBLE (250 1625);
FORCEPROP 2 LAST SEC 1
J 0
(250 1775);
DISPLAY 0.680851 (250 1775);
PAINT MONO (250 1775);
DISPLAY INVISIBLE (250 1775);
FORCEPROP 0 LAST BOM_COST SYS_CLOCK
J 0
(250 1825);
DISPLAY 1.021277 (250 1825);
PAINT ORANGE (250 1825);
DISPLAY INVISIBLE (250 1825);
FORCEPROP 2 LAST SEC_TYPE 0402
J 0
(250 1775);
DISPLAY 1.021277 (250 1775);
PAINT ORANGE (250 1775);
DISPLAY INVISIBLE (250 1775);
FORCEPROP 2 LAST CDS_LIB mstr_discrete
J 0
(300 1575);
PAINT ORANGE (300 1575);
DISPLAY INVISIBLE (300 1575);
FORCEADD OFFPAGE..1
(-675 1575);
FORCEPROP 2 LAST $XR0 102 
J 0
(-927 1575);
DISPLAY 0.638298 (-927 1575);
PAINT MONO (-927 1575);
FORCEPROP 2 LAST PATH I70
J 0
(-625 1650);
DISPLAY 1.021277 (-625 1650);
PAINT ORANGE (-625 1650);
DISPLAY INVISIBLE (-625 1650);
FORCEPROP 2 LAST CDS_LIB mstr_standard
J 0
(-675 1575);
PAINT ORANGE (-675 1575);
DISPLAY INVISIBLE (-675 1575);
FORCEPROP 1 LAST OFFPAGE TRUE
J 0
(-350 1450);
DISPLAY 0.872340 (-350 1450);
PAINT GREEN (-350 1450);
DISPLAY INVISIBLE (-350 1450);
FORCEPROP 1 LAST COMMENT_BODY TRUE
J 0
(-550 1475);
DISPLAY 0.872340 (-550 1475);
PAINT GREEN (-550 1475);
DISPLAY INVISIBLE (-550 1475);
FORCEADD OFFPAGE..2
(1950 4825);
FORCEPROP 2 LAST $XR0 36 
J 0
(2139 4825);
DISPLAY 0.638298 (2139 4825);
PAINT MONO (2139 4825);
FORCEPROP 2 LAST CDS_LIB mstr_standard
J 0
(1950 4825);
PAINT ORANGE (1950 4825);
DISPLAY INVISIBLE (1950 4825);
FORCEPROP 2 LAST PATH I71
J 0
(2125 4900);
DISPLAY 1.021277 (2125 4900);
PAINT ORANGE (2125 4900);
DISPLAY INVISIBLE (2125 4900);
FORCEPROP 1 LAST OFFPAGE TRUE
J 0
(2275 4700);
DISPLAY 0.872340 (2275 4700);
PAINT GREEN (2275 4700);
DISPLAY INVISIBLE (2275 4700);
FORCEPROP 1 LAST COMMENT_BODY TRUE
J 0
(1905 4730);
DISPLAY 0.872340 (1905 4730);
PAINT GREEN (1905 4730);
DISPLAY INVISIBLE (1905 4730);
FORCEADD RES..1
(300 4825);
FORCEPROP 1 LASTPIN (200 4825) $PN 1
J 0
(212 4837);
DISPLAY 0.617021 (212 4837);
PAINT ORANGE (212 4837);
FORCEPROP 1 LAST VALUE 27.4
J 2
(225 4775);
DISPLAY 0.617021 (225 4775);
PAINT SKYBLUE (225 4775);
FORCEPROP 1 LAST WATTAGE 1/16W
J 2
(275 4725);
DISPLAY 0.617021 (275 4725);
PAINT SKYBLUE (275 4725);
FORCEPROP 1 LAST LOCATION R4D6
J 0
(250 4875);
DISPLAY 0.617021 (250 4875);
PAINT AQUA (250 4875);
FORCEPROP 1 LASTPIN (400 4825) $PN 2
J 0
(362 4837);
DISPLAY 0.617021 (362 4837);
PAINT ORANGE (362 4837);
FORCEPROP 1 LAST MATERIAL CHIP
J 0
(350 4775);
DISPLAY 0.617021 (350 4775);
PAINT SKYBLUE (350 4775);
FORCEPROP 1 LAST PACK_TYPE 0402
J 0
(375 4725);
DISPLAY 0.617021 (375 4725);
PAINT SKYBLUE (375 4725);
FORCEPROP 1 LAST TOLERANCE 1%
J 0
(300 4725);
DISPLAY 0.617021 (300 4725);
PAINT SKYBLUE (300 4725);
FORCEPROP 1 LAST PART_NUMBER G21796-182
J 0
(425 4825);
DISPLAY 0.617021 (425 4825);
PAINT BLUE (425 4825);
FORCEPROP 0 LAST ROOM DB1200Z
J 0
(250 4975);
DISPLAY 1.021277 (250 4975);
PAINT ORANGE (250 4975);
DISPLAY INVISIBLE (250 4975);
FORCEPROP 1 LAST PATH I74
J 0
(250 4975);
DISPLAY 0.978723 (250 4975);
PAINT WHITE (250 4975);
DISPLAY INVISIBLE (250 4975);
FORCEPROP 2 LAST CDS_LOCATION R4D6
J 0
(250 4875);
DISPLAY 0.617021 (250 4875);
PAINT AQUA (250 4875);
DISPLAY INVISIBLE (250 4875);
FORCEPROP 2 LAST SEC 1
J 0
(250 5025);
DISPLAY 0.680851 (250 5025);
PAINT MONO (250 5025);
DISPLAY INVISIBLE (250 5025);
FORCEPROP 0 LAST BOM_COST SYS_CLOCK
J 0
(250 5075);
DISPLAY 1.021277 (250 5075);
PAINT ORANGE (250 5075);
DISPLAY INVISIBLE (250 5075);
FORCEPROP 2 LAST SEC_TYPE 0402
J 0
(250 5025);
DISPLAY 1.021277 (250 5025);
PAINT ORANGE (250 5025);
DISPLAY INVISIBLE (250 5025);
FORCEPROP 2 LAST CDS_LIB mstr_discrete
J 0
(300 4825);
PAINT ORANGE (300 4825);
DISPLAY INVISIBLE (300 4825);
FORCEADD OFFPAGE..1
(-675 4825);
FORCEPROP 2 LAST $XR0 102 
J 0
(-927 4825);
DISPLAY 0.638298 (-927 4825);
PAINT MONO (-927 4825);
FORCEPROP 2 LAST PATH I75
J 0
(-625 4900);
DISPLAY 1.021277 (-625 4900);
PAINT ORANGE (-625 4900);
DISPLAY INVISIBLE (-625 4900);
FORCEPROP 2 LAST CDS_LIB mstr_standard
J 0
(-675 4825);
PAINT ORANGE (-675 4825);
DISPLAY INVISIBLE (-675 4825);
FORCEPROP 1 LAST OFFPAGE TRUE
J 0
(-350 4700);
DISPLAY 0.872340 (-350 4700);
PAINT GREEN (-350 4700);
DISPLAY INVISIBLE (-350 4700);
FORCEPROP 1 LAST COMMENT_BODY TRUE
J 0
(-550 4725);
DISPLAY 0.872340 (-550 4725);
PAINT GREEN (-550 4725);
DISPLAY INVISIBLE (-550 4725);
FORCEADD OFFPAGE..2
(1950 4500);
FORCEPROP 2 LAST $XR0 36 
J 0
(2139 4500);
DISPLAY 0.638298 (2139 4500);
PAINT MONO (2139 4500);
FORCEPROP 2 LAST CDS_LIB mstr_standard
J 0
(1950 4500);
PAINT ORANGE (1950 4500);
DISPLAY INVISIBLE (1950 4500);
FORCEPROP 2 LAST PATH I77
J 0
(2125 4575);
DISPLAY 1.021277 (2125 4575);
PAINT ORANGE (2125 4575);
DISPLAY INVISIBLE (2125 4575);
FORCEPROP 1 LAST OFFPAGE TRUE
J 0
(2275 4375);
DISPLAY 0.872340 (2275 4375);
PAINT GREEN (2275 4375);
DISPLAY INVISIBLE (2275 4375);
FORCEPROP 1 LAST COMMENT_BODY TRUE
J 0
(1905 4405);
DISPLAY 0.872340 (1905 4405);
PAINT GREEN (1905 4405);
DISPLAY INVISIBLE (1905 4405);
FORCEADD RES..1
(300 4500);
FORCEPROP 1 LASTPIN (200 4500) $PN 1
J 0
(212 4512);
DISPLAY 0.617021 (212 4512);
PAINT ORANGE (212 4512);
FORCEPROP 1 LAST VALUE 27.4
J 2
(225 4450);
DISPLAY 0.617021 (225 4450);
PAINT SKYBLUE (225 4450);
FORCEPROP 1 LAST WATTAGE 1/16W
J 2
(275 4400);
DISPLAY 0.617021 (275 4400);
PAINT SKYBLUE (275 4400);
FORCEPROP 1 LAST LOCATION R4D5
J 0
(250 4550);
DISPLAY 0.617021 (250 4550);
PAINT AQUA (250 4550);
FORCEPROP 1 LASTPIN (400 4500) $PN 2
J 0
(362 4512);
DISPLAY 0.617021 (362 4512);
PAINT ORANGE (362 4512);
FORCEPROP 1 LAST MATERIAL CHIP
J 0
(350 4450);
DISPLAY 0.617021 (350 4450);
PAINT SKYBLUE (350 4450);
FORCEPROP 1 LAST PACK_TYPE 0402
J 0
(375 4400);
DISPLAY 0.617021 (375 4400);
PAINT SKYBLUE (375 4400);
FORCEPROP 1 LAST TOLERANCE 1%
J 0
(300 4400);
DISPLAY 0.617021 (300 4400);
PAINT SKYBLUE (300 4400);
FORCEPROP 1 LAST PART_NUMBER G21796-182
J 0
(425 4500);
DISPLAY 0.617021 (425 4500);
PAINT BLUE (425 4500);
FORCEPROP 2 LAST CDS_LOCATION R4D5
J 0
(250 4550);
DISPLAY 0.617021 (250 4550);
PAINT AQUA (250 4550);
DISPLAY INVISIBLE (250 4550);
FORCEPROP 2 LAST CDS_LIB mstr_discrete
J 0
(300 4500);
PAINT ORANGE (300 4500);
DISPLAY INVISIBLE (300 4500);
FORCEPROP 2 LAST SEC_TYPE 0402
J 0
(250 4700);
DISPLAY 1.021277 (250 4700);
PAINT ORANGE (250 4700);
DISPLAY INVISIBLE (250 4700);
FORCEPROP 0 LAST BOM_COST SYS_CLOCK
J 0
(250 4750);
DISPLAY 1.021277 (250 4750);
PAINT ORANGE (250 4750);
DISPLAY INVISIBLE (250 4750);
FORCEPROP 2 LAST SEC 1
J 0
(250 4700);
DISPLAY 0.680851 (250 4700);
PAINT MONO (250 4700);
DISPLAY INVISIBLE (250 4700);
FORCEPROP 1 LAST PATH I79
J 0
(250 4650);
DISPLAY 0.978723 (250 4650);
PAINT WHITE (250 4650);
DISPLAY INVISIBLE (250 4650);
FORCEPROP 0 LAST ROOM DB1200Z
J 0
(250 4650);
DISPLAY 1.021277 (250 4650);
PAINT ORANGE (250 4650);
DISPLAY INVISIBLE (250 4650);
FORCEADD OFFPAGE..1
(-675 4500);
FORCEPROP 2 LAST $XR0 102 
J 0
(-927 4500);
DISPLAY 0.638298 (-927 4500);
PAINT MONO (-927 4500);
FORCEPROP 2 LAST CDS_LIB mstr_standard
J 0
(-675 4500);
PAINT ORANGE (-675 4500);
DISPLAY INVISIBLE (-675 4500);
FORCEPROP 2 LAST PATH I80
J 0
(-625 4575);
DISPLAY 1.021277 (-625 4575);
PAINT ORANGE (-625 4575);
DISPLAY INVISIBLE (-625 4575);
FORCEPROP 1 LAST OFFPAGE TRUE
J 0
(-350 4375);
DISPLAY 0.872340 (-350 4375);
PAINT GREEN (-350 4375);
DISPLAY INVISIBLE (-350 4375);
FORCEPROP 1 LAST COMMENT_BODY TRUE
J 0
(-550 4400);
DISPLAY 0.872340 (-550 4400);
PAINT GREEN (-550 4400);
DISPLAY INVISIBLE (-550 4400);
FORCEADD OFFPAGE..2
(1950 4175);
FORCEPROP 2 LAST $XR0 22 
J 0
(2139 4175);
DISPLAY 0.638298 (2139 4175);
PAINT MONO (2139 4175);
FORCEPROP 2 LAST CDS_LIB mstr_standard
J 0
(1950 4175);
PAINT ORANGE (1950 4175);
DISPLAY INVISIBLE (1950 4175);
FORCEPROP 2 LAST PATH I82
J 0
(2125 4250);
DISPLAY 1.021277 (2125 4250);
PAINT ORANGE (2125 4250);
DISPLAY INVISIBLE (2125 4250);
FORCEPROP 1 LAST OFFPAGE TRUE
J 0
(2275 4050);
DISPLAY 0.872340 (2275 4050);
PAINT GREEN (2275 4050);
DISPLAY INVISIBLE (2275 4050);
FORCEPROP 1 LAST COMMENT_BODY TRUE
J 0
(1905 4080);
DISPLAY 0.872340 (1905 4080);
PAINT GREEN (1905 4080);
DISPLAY INVISIBLE (1905 4080);
FORCEADD RES..1
(300 4175);
FORCEPROP 1 LAST WATTAGE 1/16W
J 2
(275 4075);
DISPLAY 0.617021 (275 4075);
PAINT SKYBLUE (275 4075);
FORCEPROP 1 LAST PACK_TYPE 0402
J 0
(375 4075);
DISPLAY 0.617021 (375 4075);
PAINT SKYBLUE (375 4075);
FORCEPROP 1 LAST TOLERANCE 1%
J 0
(300 4075);
DISPLAY 0.617021 (300 4075);
PAINT SKYBLUE (300 4075);
FORCEPROP 1 LASTPIN (200 4175) $PN 1
J 0
(212 4187);
DISPLAY 0.617021 (212 4187);
PAINT ORANGE (212 4187);
FORCEPROP 1 LAST VALUE 27.4
J 2
(225 4125);
DISPLAY 0.617021 (225 4125);
PAINT SKYBLUE (225 4125);
FORCEPROP 1 LAST LOCATION R4D8
J 0
(250 4225);
DISPLAY 0.617021 (250 4225);
PAINT AQUA (250 4225);
FORCEPROP 1 LASTPIN (400 4175) $PN 2
J 0
(362 4187);
DISPLAY 0.617021 (362 4187);
PAINT ORANGE (362 4187);
FORCEPROP 1 LAST MATERIAL CHIP
J 0
(350 4125);
DISPLAY 0.617021 (350 4125);
PAINT SKYBLUE (350 4125);
FORCEPROP 1 LAST PART_NUMBER G21796-182
J 0
(425 4175);
DISPLAY 0.617021 (425 4175);
PAINT BLUE (425 4175);
FORCEPROP 0 LAST ROOM DB1200Z
J 0
(250 4325);
DISPLAY 1.021277 (250 4325);
PAINT ORANGE (250 4325);
DISPLAY INVISIBLE (250 4325);
FORCEPROP 1 LAST PATH I84
J 0
(250 4325);
DISPLAY 0.978723 (250 4325);
PAINT WHITE (250 4325);
DISPLAY INVISIBLE (250 4325);
FORCEPROP 2 LAST CDS_LOCATION R4D8
J 0
(250 4225);
DISPLAY 0.617021 (250 4225);
PAINT AQUA (250 4225);
DISPLAY INVISIBLE (250 4225);
FORCEPROP 2 LAST SEC 1
J 0
(250 4375);
DISPLAY 0.680851 (250 4375);
PAINT MONO (250 4375);
DISPLAY INVISIBLE (250 4375);
FORCEPROP 0 LAST BOM_COST SYS_CLOCK
J 0
(250 4425);
DISPLAY 1.021277 (250 4425);
PAINT ORANGE (250 4425);
DISPLAY INVISIBLE (250 4425);
FORCEPROP 2 LAST SEC_TYPE 0402
J 0
(250 4375);
DISPLAY 1.021277 (250 4375);
PAINT ORANGE (250 4375);
DISPLAY INVISIBLE (250 4375);
FORCEPROP 2 LAST CDS_LIB mstr_discrete
J 0
(300 4175);
PAINT ORANGE (300 4175);
DISPLAY INVISIBLE (300 4175);
FORCEADD OFFPAGE..1
(-675 4175);
FORCEPROP 2 LAST $XR0 102 
J 0
(-927 4175);
DISPLAY 0.638298 (-927 4175);
PAINT MONO (-927 4175);
FORCEPROP 2 LAST PATH I85
J 0
(-625 4250);
DISPLAY 1.021277 (-625 4250);
PAINT ORANGE (-625 4250);
DISPLAY INVISIBLE (-625 4250);
FORCEPROP 2 LAST CDS_LIB mstr_standard
J 0
(-675 4175);
PAINT ORANGE (-675 4175);
DISPLAY INVISIBLE (-675 4175);
FORCEPROP 1 LAST OFFPAGE TRUE
J 0
(-350 4050);
DISPLAY 0.872340 (-350 4050);
PAINT GREEN (-350 4050);
DISPLAY INVISIBLE (-350 4050);
FORCEPROP 1 LAST COMMENT_BODY TRUE
J 0
(-550 4075);
DISPLAY 0.872340 (-550 4075);
PAINT GREEN (-550 4075);
DISPLAY INVISIBLE (-550 4075);
FORCEADD OFFPAGE..2
(1950 3850);
FORCEPROP 2 LAST $XR0 22 
J 0
(2139 3850);
DISPLAY 0.638298 (2139 3850);
PAINT MONO (2139 3850);
FORCEPROP 2 LAST CDS_LIB mstr_standard
J 0
(1950 3850);
PAINT ORANGE (1950 3850);
DISPLAY INVISIBLE (1950 3850);
FORCEPROP 2 LAST PATH I87
J 0
(2125 3925);
DISPLAY 1.021277 (2125 3925);
PAINT ORANGE (2125 3925);
DISPLAY INVISIBLE (2125 3925);
FORCEPROP 1 LAST OFFPAGE TRUE
J 0
(2275 3725);
DISPLAY 0.872340 (2275 3725);
PAINT GREEN (2275 3725);
DISPLAY INVISIBLE (2275 3725);
FORCEPROP 1 LAST COMMENT_BODY TRUE
J 0
(1905 3755);
DISPLAY 0.872340 (1905 3755);
PAINT GREEN (1905 3755);
DISPLAY INVISIBLE (1905 3755);
FORCEADD RES..1
(300 3850);
FORCEPROP 1 LASTPIN (200 3850) $PN 1
J 0
(212 3862);
DISPLAY 0.617021 (212 3862);
PAINT ORANGE (212 3862);
FORCEPROP 1 LAST VALUE 27.4
J 2
(225 3800);
DISPLAY 0.617021 (225 3800);
PAINT SKYBLUE (225 3800);
FORCEPROP 1 LAST WATTAGE 1/16W
J 2
(275 3750);
DISPLAY 0.617021 (275 3750);
PAINT SKYBLUE (275 3750);
FORCEPROP 1 LAST LOCATION R4D7
J 0
(250 3900);
DISPLAY 0.617021 (250 3900);
PAINT AQUA (250 3900);
FORCEPROP 1 LASTPIN (400 3850) $PN 2
J 0
(362 3862);
DISPLAY 0.617021 (362 3862);
PAINT ORANGE (362 3862);
FORCEPROP 1 LAST MATERIAL CHIP
J 0
(350 3800);
DISPLAY 0.617021 (350 3800);
PAINT SKYBLUE (350 3800);
FORCEPROP 1 LAST PACK_TYPE 0402
J 0
(375 3750);
DISPLAY 0.617021 (375 3750);
PAINT SKYBLUE (375 3750);
FORCEPROP 1 LAST TOLERANCE 1%
J 0
(300 3750);
DISPLAY 0.617021 (300 3750);
PAINT SKYBLUE (300 3750);
FORCEPROP 1 LAST PART_NUMBER G21796-182
J 0
(425 3850);
DISPLAY 0.617021 (425 3850);
PAINT BLUE (425 3850);
FORCEPROP 0 LAST ROOM DB1200Z
J 0
(250 4000);
DISPLAY 1.021277 (250 4000);
PAINT ORANGE (250 4000);
DISPLAY INVISIBLE (250 4000);
FORCEPROP 1 LAST PATH I89
J 0
(250 4000);
DISPLAY 0.978723 (250 4000);
PAINT WHITE (250 4000);
DISPLAY INVISIBLE (250 4000);
FORCEPROP 2 LAST CDS_LOCATION R4D7
J 0
(250 3900);
DISPLAY 0.617021 (250 3900);
PAINT AQUA (250 3900);
DISPLAY INVISIBLE (250 3900);
FORCEPROP 2 LAST SEC 1
J 0
(250 4050);
DISPLAY 0.680851 (250 4050);
PAINT MONO (250 4050);
DISPLAY INVISIBLE (250 4050);
FORCEPROP 2 LAST SEC_TYPE 0402
J 0
(250 4050);
DISPLAY 1.021277 (250 4050);
PAINT ORANGE (250 4050);
DISPLAY INVISIBLE (250 4050);
FORCEPROP 2 LAST CDS_LIB mstr_discrete
J 0
(300 3850);
PAINT ORANGE (300 3850);
DISPLAY INVISIBLE (300 3850);
FORCEPROP 0 LAST BOM_COST SYS_CLOCK
J 0
(250 4100);
DISPLAY 1.021277 (250 4100);
PAINT ORANGE (250 4100);
DISPLAY INVISIBLE (250 4100);
FORCEADD RES..1
(-3925 4900);
FORCEPROP 1 LAST LOCATION R4D23
J 0
(-3975 4950);
DISPLAY 0.617021 (-3975 4950);
PAINT AQUA (-3975 4950);
FORCEPROP 1 LAST VALUE 27.4
J 2
(-4000 4850);
DISPLAY 0.617021 (-4000 4850);
PAINT SKYBLUE (-4000 4850);
FORCEPROP 1 LAST WATTAGE 1/16W
J 2
(-3950 4800);
DISPLAY 0.617021 (-3950 4800);
PAINT SKYBLUE (-3950 4800);
FORCEPROP 1 LAST TOLERANCE 1%
J 0
(-3925 4800);
DISPLAY 0.617021 (-3925 4800);
PAINT SKYBLUE (-3925 4800);
FORCEPROP 1 LASTPIN (-4025 4900) $PN 1
J 0
(-4013 4912);
DISPLAY 0.617021 (-4013 4912);
PAINT ORANGE (-4013 4912);
FORCEPROP 1 LASTPIN (-3825 4900) $PN 2
J 0
(-3863 4912);
DISPLAY 0.617021 (-3863 4912);
PAINT ORANGE (-3863 4912);
FORCEPROP 1 LAST PART_NUMBER G21796-182
J 0
(-4075 4750);
DISPLAY 0.617021 (-4075 4750);
PAINT BLUE (-4075 4750);
FORCEPROP 1 LAST MATERIAL CHIP
J 0
(-3875 4850);
DISPLAY 0.617021 (-3875 4850);
PAINT SKYBLUE (-3875 4850);
FORCEPROP 1 LAST PACK_TYPE 0402
J 0
(-3850 4800);
DISPLAY 0.617021 (-3850 4800);
PAINT SKYBLUE (-3850 4800);
FORCEPROP 0 LAST ROOM DB1200Z
J 0
(-3975 5050);
DISPLAY 1.021277 (-3975 5050);
PAINT ORANGE (-3975 5050);
DISPLAY INVISIBLE (-3975 5050);
FORCEPROP 1 LAST PATH I9
J 0
(-3975 5050);
DISPLAY 0.978723 (-3975 5050);
PAINT WHITE (-3975 5050);
DISPLAY INVISIBLE (-3975 5050);
FORCEPROP 2 LAST CDS_LOCATION R4D23
J 0
(-3975 4950);
DISPLAY 0.617021 (-3975 4950);
PAINT AQUA (-3975 4950);
DISPLAY INVISIBLE (-3975 4950);
FORCEPROP 2 LAST CDS_LIB mstr_discrete
J 0
(-3925 4900);
PAINT ORANGE (-3925 4900);
DISPLAY INVISIBLE (-3925 4900);
FORCEPROP 2 LAST SEC 1
J 0
(-3975 5100);
DISPLAY 0.680851 (-3975 5100);
PAINT MONO (-3975 5100);
DISPLAY INVISIBLE (-3975 5100);
FORCEPROP 2 LAST SEC_TYPE 0402
J 0
(-3975 5100);
DISPLAY 1.021277 (-3975 5100);
PAINT ORANGE (-3975 5100);
DISPLAY INVISIBLE (-3975 5100);
FORCEPROP 0 LAST BOM_COST SYS_CLOCK
J 0
(-3975 5150);
DISPLAY 1.021277 (-3975 5150);
PAINT ORANGE (-3975 5150);
DISPLAY INVISIBLE (-3975 5150);
FORCEADD OFFPAGE..1
(-675 3850);
FORCEPROP 2 LAST $XR0 102 
J 0
(-927 3850);
DISPLAY 0.638298 (-927 3850);
PAINT MONO (-927 3850);
FORCEPROP 2 LAST PATH I90
J 0
(-625 3925);
DISPLAY 1.021277 (-625 3925);
PAINT ORANGE (-625 3925);
DISPLAY INVISIBLE (-625 3925);
FORCEPROP 2 LAST CDS_LIB mstr_standard
J 0
(-675 3850);
PAINT ORANGE (-675 3850);
DISPLAY INVISIBLE (-675 3850);
FORCEPROP 1 LAST OFFPAGE TRUE
J 0
(-350 3725);
DISPLAY 0.872340 (-350 3725);
PAINT GREEN (-350 3725);
DISPLAY INVISIBLE (-350 3725);
FORCEPROP 1 LAST COMMENT_BODY TRUE
J 0
(-550 3750);
DISPLAY 0.872340 (-550 3750);
PAINT GREEN (-550 3750);
DISPLAY INVISIBLE (-550 3750);
FORCEADD OFFPAGE..2
(1950 3525);
FORCEPROP 2 LAST $XR0 29 
J 0
(2139 3525);
DISPLAY 0.638298 (2139 3525);
PAINT MONO (2139 3525);
FORCEPROP 2 LAST CDS_LIB mstr_standard
J 0
(1950 3525);
PAINT ORANGE (1950 3525);
DISPLAY INVISIBLE (1950 3525);
FORCEPROP 2 LAST PATH I92
J 0
(2125 3600);
DISPLAY 1.021277 (2125 3600);
PAINT ORANGE (2125 3600);
DISPLAY INVISIBLE (2125 3600);
FORCEPROP 1 LAST OFFPAGE TRUE
J 0
(2275 3400);
DISPLAY 0.872340 (2275 3400);
PAINT GREEN (2275 3400);
DISPLAY INVISIBLE (2275 3400);
FORCEPROP 1 LAST COMMENT_BODY TRUE
J 0
(1905 3430);
DISPLAY 0.872340 (1905 3430);
PAINT GREEN (1905 3430);
DISPLAY INVISIBLE (1905 3430);
FORCEADD RES..1
(300 3525);
FORCEPROP 1 LAST VALUE 27.4
J 2
(225 3475);
DISPLAY 0.617021 (225 3475);
PAINT SKYBLUE (225 3475);
FORCEPROP 1 LASTPIN (200 3525) $PN 1
J 0
(212 3537);
DISPLAY 0.617021 (212 3537);
PAINT ORANGE (212 3537);
FORCEPROP 1 LAST WATTAGE 1/16W
J 2
(275 3425);
DISPLAY 0.617021 (275 3425);
PAINT SKYBLUE (275 3425);
FORCEPROP 1 LASTPIN (400 3525) $PN 2
J 0
(362 3537);
DISPLAY 0.617021 (362 3537);
PAINT ORANGE (362 3537);
FORCEPROP 1 LAST MATERIAL CHIP
J 0
(350 3475);
DISPLAY 0.617021 (350 3475);
PAINT SKYBLUE (350 3475);
FORCEPROP 1 LAST PACK_TYPE 0402
J 0
(375 3425);
DISPLAY 0.617021 (375 3425);
PAINT SKYBLUE (375 3425);
FORCEPROP 1 LAST TOLERANCE 1%
J 0
(300 3425);
DISPLAY 0.617021 (300 3425);
PAINT SKYBLUE (300 3425);
FORCEPROP 1 LAST LOCATION R4D12
J 0
(250 3575);
DISPLAY 0.617021 (250 3575);
PAINT AQUA (250 3575);
FORCEPROP 1 LAST PART_NUMBER G21796-182
J 0
(425 3525);
DISPLAY 0.617021 (425 3525);
PAINT BLUE (425 3525);
FORCEPROP 2 LAST CDS_LIB mstr_discrete
J 0
(300 3525);
PAINT ORANGE (300 3525);
DISPLAY INVISIBLE (300 3525);
FORCEPROP 2 LAST CDS_LOCATION R4D12
J 0
(250 3575);
DISPLAY 0.617021 (250 3575);
PAINT AQUA (250 3575);
DISPLAY INVISIBLE (250 3575);
FORCEPROP 0 LAST BOM_COST SYS_CLOCK
J 0
(250 3775);
DISPLAY 1.021277 (250 3775);
PAINT ORANGE (250 3775);
DISPLAY INVISIBLE (250 3775);
FORCEPROP 2 LAST SEC_TYPE 0402
J 0
(250 3725);
DISPLAY 1.021277 (250 3725);
PAINT ORANGE (250 3725);
DISPLAY INVISIBLE (250 3725);
FORCEPROP 2 LAST SEC 1
J 0
(250 3725);
DISPLAY 0.680851 (250 3725);
PAINT MONO (250 3725);
DISPLAY INVISIBLE (250 3725);
FORCEPROP 1 LAST PATH I94
J 0
(250 3675);
DISPLAY 0.978723 (250 3675);
PAINT WHITE (250 3675);
DISPLAY INVISIBLE (250 3675);
FORCEPROP 0 LAST ROOM DB1200Z
J 0
(250 3675);
DISPLAY 1.021277 (250 3675);
PAINT ORANGE (250 3675);
DISPLAY INVISIBLE (250 3675);
FORCEADD OFFPAGE..1
(-675 3525);
FORCEPROP 2 LAST $XR0 102 
J 0
(-927 3525);
DISPLAY 0.638298 (-927 3525);
PAINT MONO (-927 3525);
FORCEPROP 2 LAST CDS_LIB mstr_standard
J 0
(-675 3525);
PAINT ORANGE (-675 3525);
DISPLAY INVISIBLE (-675 3525);
FORCEPROP 2 LAST PATH I95
J 0
(-625 3600);
DISPLAY 1.021277 (-625 3600);
PAINT ORANGE (-625 3600);
DISPLAY INVISIBLE (-625 3600);
FORCEPROP 1 LAST OFFPAGE TRUE
J 0
(-350 3400);
DISPLAY 0.872340 (-350 3400);
PAINT GREEN (-350 3400);
DISPLAY INVISIBLE (-350 3400);
FORCEPROP 1 LAST COMMENT_BODY TRUE
J 0
(-550 3425);
DISPLAY 0.872340 (-550 3425);
PAINT GREEN (-550 3425);
DISPLAY INVISIBLE (-550 3425);
FORCEADD OFFPAGE..2
(1950 3200);
FORCEPROP 2 LAST $XR0 29 
J 0
(2139 3200);
DISPLAY 0.638298 (2139 3200);
PAINT MONO (2139 3200);
FORCEPROP 2 LAST CDS_LIB mstr_standard
J 0
(1950 3200);
PAINT ORANGE (1950 3200);
DISPLAY INVISIBLE (1950 3200);
FORCEPROP 2 LAST PATH I97
J 0
(2125 3275);
DISPLAY 1.021277 (2125 3275);
PAINT ORANGE (2125 3275);
DISPLAY INVISIBLE (2125 3275);
FORCEPROP 1 LAST OFFPAGE TRUE
J 0
(2275 3075);
DISPLAY 0.872340 (2275 3075);
PAINT GREEN (2275 3075);
DISPLAY INVISIBLE (2275 3075);
FORCEPROP 1 LAST COMMENT_BODY TRUE
J 0
(1905 3105);
DISPLAY 0.872340 (1905 3105);
PAINT GREEN (1905 3105);
DISPLAY INVISIBLE (1905 3105);
FORCEADD RES..1
(300 3200);
FORCEPROP 1 LAST VALUE 27.4
J 2
(225 3150);
DISPLAY 0.617021 (225 3150);
PAINT SKYBLUE (225 3150);
FORCEPROP 1 LASTPIN (200 3200) $PN 1
J 0
(212 3187);
DISPLAY 0.617021 (212 3187);
PAINT ORANGE (212 3187);
FORCEPROP 1 LAST WATTAGE 1/16W
J 2
(275 3100);
DISPLAY 0.617021 (275 3100);
PAINT SKYBLUE (275 3100);
FORCEPROP 1 LAST LOCATION R4D10
J 0
(250 3225);
DISPLAY 0.617021 (250 3225);
PAINT AQUA (250 3225);
FORCEPROP 1 LASTPIN (400 3200) $PN 2
J 0
(362 3187);
DISPLAY 0.617021 (362 3187);
PAINT ORANGE (362 3187);
FORCEPROP 1 LAST MATERIAL CHIP
J 0
(350 3150);
DISPLAY 0.617021 (350 3150);
PAINT SKYBLUE (350 3150);
FORCEPROP 1 LAST PACK_TYPE 0402
J 0
(375 3100);
DISPLAY 0.617021 (375 3100);
PAINT SKYBLUE (375 3100);
FORCEPROP 1 LAST TOLERANCE 1%
J 0
(300 3100);
DISPLAY 0.617021 (300 3100);
PAINT SKYBLUE (300 3100);
FORCEPROP 1 LAST PART_NUMBER G21796-182
J 0
(425 3200);
DISPLAY 0.617021 (425 3200);
PAINT BLUE (425 3200);
FORCEPROP 2 LAST CDS_LOCATION R4D10
J 0
(250 3225);
DISPLAY 0.617021 (250 3225);
PAINT AQUA (250 3225);
DISPLAY INVISIBLE (250 3225);
FORCEPROP 0 LAST ROOM DB1200Z
J 0
(250 3325);
DISPLAY 1.021277 (250 3325);
PAINT ORANGE (250 3325);
DISPLAY INVISIBLE (250 3325);
FORCEPROP 0 LAST BOM_COST SYS_CLOCK
J 0
(250 3425);
DISPLAY 1.021277 (250 3425);
PAINT ORANGE (250 3425);
DISPLAY INVISIBLE (250 3425);
FORCEPROP 2 LAST SEC_TYPE 0402
J 0
(250 3400);
DISPLAY 1.021277 (250 3400);
PAINT ORANGE (250 3400);
DISPLAY INVISIBLE (250 3400);
FORCEPROP 2 LAST SEC 1
J 0
(250 3400);
DISPLAY 0.680851 (250 3400);
PAINT MONO (250 3400);
DISPLAY INVISIBLE (250 3400);
FORCEPROP 1 LAST PATH I99
J 0
(250 3350);
DISPLAY 0.978723 (250 3350);
PAINT WHITE (250 3350);
DISPLAY INVISIBLE (250 3350);
FORCEPROP 2 LAST CDS_LIB mstr_discrete
J 0
(300 3200);
PAINT ORANGE (300 3200);
DISPLAY INVISIBLE (300 3200);
FORCEADD DESIGN_NOTE..1
(-200 5350);
FORCEPROP 0 LAST L2 REQUIRED WITH -ZL VERSION
J 0
(-400 5150);
DISPLAY 1.021277 (-400 5150);
PAINT ORANGE (-400 5150);
FORCEPROP 0 LAST L1 PARALLEL RESISTORS ARE NOT
J 0
(-400 5225);
DISPLAY 1.021277 (-400 5225);
PAINT ORANGE (-400 5225);
FORCEPROP 0 LAST L3 ONLY REQUIRED WITH -L VERSION
J 0
(-400 5075);
DISPLAY 1.021277 (-400 5075);
PAINT ORANGE (-400 5075);
FORCEPROP 2 LAST CDS_LIB mstr_symbols
J 0
(-200 5350);
PAINT MONO (-200 5350);
DISPLAY INVISIBLE (-200 5350);
FORCEPROP 1 LAST COMMENT_BODY TRUE
J 0
(-175 5450);
DISPLAY 0.978723 (-175 5450);
PAINT ORANGE (-175 5450);
DISPLAY INVISIBLE (-175 5450);
FORCEADD DNS..2
(-3320 4795);
PAINT RED (-3320 4795);
FORCEPROP 2 LAST CDS_LIB mstr_misc
J 0
(-3320 4795);
PAINT ORANGE (-3320 4795);
DISPLAY INVISIBLE (-3320 4795);
FORCEPROP 1 LAST COMMENT_BODY TRUE
R 1
J 0
(-3245 4570);
DISPLAY 0.872340 (-3245 4570);
PAINT GREEN (-3245 4570);
DISPLAY INVISIBLE (-3245 4570);
FORCEADD DNS..2
(-3320 3745);
PAINT RED (-3320 3745);
FORCEPROP 2 LAST CDS_LIB mstr_misc
J 0
(-3320 3745);
PAINT ORANGE (-3320 3745);
DISPLAY INVISIBLE (-3320 3745);
FORCEPROP 1 LAST COMMENT_BODY TRUE
R 1
J 0
(-3245 3520);
DISPLAY 0.872340 (-3245 3520);
PAINT GREEN (-3245 3520);
DISPLAY INVISIBLE (-3245 3520);
FORCEADD DNS..2
(-3320 4070);
PAINT RED (-3320 4070);
FORCEPROP 2 LAST CDS_LIB mstr_misc
J 0
(-3320 4070);
PAINT ORANGE (-3320 4070);
DISPLAY INVISIBLE (-3320 4070);
FORCEPROP 1 LAST COMMENT_BODY TRUE
R 1
J 0
(-3245 3845);
DISPLAY 0.872340 (-3245 3845);
PAINT GREEN (-3245 3845);
DISPLAY INVISIBLE (-3245 3845);
FORCEADD DNS..2
(1030 4070);
PAINT RED (1030 4070);
FORCEPROP 2 LAST CDS_LIB mstr_misc
J 0
(1030 4070);
PAINT ORANGE (1030 4070);
DISPLAY INVISIBLE (1030 4070);
FORCEPROP 1 LAST COMMENT_BODY TRUE
R 1
J 0
(1105 3845);
DISPLAY 0.872340 (1105 3845);
PAINT GREEN (1105 3845);
DISPLAY INVISIBLE (1105 3845);
FORCEADD DNS..2
(-3320 2770);
PAINT RED (-3320 2770);
FORCEPROP 2 LAST CDS_LIB mstr_misc
J 0
(-3320 2770);
PAINT ORANGE (-3320 2770);
DISPLAY INVISIBLE (-3320 2770);
FORCEPROP 1 LAST COMMENT_BODY TRUE
R 1
J 0
(-3245 2545);
DISPLAY 0.872340 (-3245 2545);
PAINT GREEN (-3245 2545);
DISPLAY INVISIBLE (-3245 2545);
FORCEADD DNS..2
(-3320 2445);
PAINT RED (-3320 2445);
FORCEPROP 2 LAST CDS_LIB mstr_misc
J 0
(-3320 2445);
PAINT ORANGE (-3320 2445);
DISPLAY INVISIBLE (-3320 2445);
FORCEPROP 1 LAST COMMENT_BODY TRUE
R 1
J 0
(-3245 2220);
DISPLAY 0.872340 (-3245 2220);
PAINT GREEN (-3245 2220);
DISPLAY INVISIBLE (-3245 2220);
FORCEADD DNS..2
(-3320 2120);
PAINT RED (-3320 2120);
FORCEPROP 2 LAST CDS_LIB mstr_misc
J 0
(-3320 2120);
PAINT ORANGE (-3320 2120);
DISPLAY INVISIBLE (-3320 2120);
FORCEPROP 1 LAST COMMENT_BODY TRUE
R 1
J 0
(-3245 1895);
DISPLAY 0.872340 (-3245 1895);
PAINT GREEN (-3245 1895);
DISPLAY INVISIBLE (-3245 1895);
FORCEADD DNS..2
(-3320 1795);
PAINT RED (-3320 1795);
FORCEPROP 2 LAST CDS_LIB mstr_misc
J 0
(-3320 1795);
PAINT ORANGE (-3320 1795);
DISPLAY INVISIBLE (-3320 1795);
FORCEPROP 1 LAST COMMENT_BODY TRUE
R 1
J 0
(-3245 1570);
DISPLAY 0.872340 (-3245 1570);
PAINT GREEN (-3245 1570);
DISPLAY INVISIBLE (-3245 1570);
FORCEADD DNS..2
(-3320 3095);
PAINT RED (-3320 3095);
FORCEPROP 2 LAST CDS_LIB mstr_misc
J 0
(-3320 3095);
PAINT ORANGE (-3320 3095);
DISPLAY INVISIBLE (-3320 3095);
FORCEPROP 1 LAST COMMENT_BODY TRUE
R 1
J 0
(-3245 2870);
DISPLAY 0.872340 (-3245 2870);
PAINT GREEN (-3245 2870);
DISPLAY INVISIBLE (-3245 2870);
FORCEADD CAD_NOTE..1
(1200 5300);
FORCEPROP 0 LAST L1 PLACE RESISTORS CLOSE TO CLK
J 0
(1050 5175);
DISPLAY 1.021277 (1050 5175);
PAINT ORANGE (1050 5175);
FORCEPROP 0 LAST L2 SOURCE WITHIN 0.5 INCHES
J 0
(1050 5100);
DISPLAY 1.021277 (1050 5100);
PAINT ORANGE (1050 5100);
FORCEPROP 2 LAST CDS_LIB mstr_symbols
J 0
(1200 5300);
PAINT ORANGE (1200 5300);
DISPLAY INVISIBLE (1200 5300);
FORCEPROP 1 LAST COMMENT_BODY TRUE
J 0
(1225 5400);
DISPLAY 0.978723 (1225 5400);
PAINT ORANGE (1225 5400);
DISPLAY INVISIBLE (1225 5400);
FORCEADD DNS..2
(1030 4720);
PAINT RED (1030 4720);
FORCEPROP 2 LAST CDS_LIB mstr_misc
J 0
(1030 4720);
PAINT ORANGE (1030 4720);
DISPLAY INVISIBLE (1030 4720);
FORCEPROP 1 LAST COMMENT_BODY TRUE
R 1
J 0
(1105 4495);
DISPLAY 0.872340 (1105 4495);
PAINT GREEN (1105 4495);
DISPLAY INVISIBLE (1105 4495);
FORCEADD DNS..2
(-3320 3420);
PAINT RED (-3320 3420);
FORCEPROP 2 LAST CDS_LIB mstr_misc
J 0
(-3320 3420);
PAINT ORANGE (-3320 3420);
DISPLAY INVISIBLE (-3320 3420);
FORCEPROP 1 LAST COMMENT_BODY TRUE
R 1
J 0
(-3245 3195);
DISPLAY 0.872340 (-3245 3195);
PAINT GREEN (-3245 3195);
DISPLAY INVISIBLE (-3245 3195);
FORCEADD DNS..2
(1055 3745);
PAINT RED (1055 3745);
FORCEPROP 2 LAST CDS_LIB mstr_misc
J 0
(1055 3745);
PAINT ORANGE (1055 3745);
DISPLAY INVISIBLE (1055 3745);
FORCEPROP 1 LAST COMMENT_BODY TRUE
R 1
J 0
(1130 3520);
DISPLAY 0.872340 (1130 3520);
PAINT GREEN (1130 3520);
DISPLAY INVISIBLE (1130 3520);
FORCEADD DNS..2
(1055 3420);
PAINT RED (1055 3420);
FORCEPROP 2 LAST CDS_LIB mstr_misc
J 0
(1055 3420);
PAINT ORANGE (1055 3420);
DISPLAY INVISIBLE (1055 3420);
FORCEPROP 1 LAST COMMENT_BODY TRUE
R 1
J 0
(1130 3195);
DISPLAY 0.872340 (1130 3195);
PAINT GREEN (1130 3195);
DISPLAY INVISIBLE (1130 3195);
FORCEADD DNS..2
(1080 3095);
PAINT RED (1080 3095);
FORCEPROP 2 LAST CDS_LIB mstr_misc
J 0
(1080 3095);
PAINT ORANGE (1080 3095);
DISPLAY INVISIBLE (1080 3095);
FORCEPROP 1 LAST COMMENT_BODY TRUE
R 1
J 0
(1155 2870);
DISPLAY 0.872340 (1155 2870);
PAINT GREEN (1155 2870);
DISPLAY INVISIBLE (1155 2870);
FORCEADD DNS..2
(1055 2770);
PAINT RED (1055 2770);
FORCEPROP 2 LAST CDS_LIB mstr_misc
J 0
(1055 2770);
PAINT ORANGE (1055 2770);
DISPLAY INVISIBLE (1055 2770);
FORCEPROP 1 LAST COMMENT_BODY TRUE
R 1
J 0
(1130 2545);
DISPLAY 0.872340 (1130 2545);
PAINT GREEN (1130 2545);
DISPLAY INVISIBLE (1130 2545);
FORCEADD DNS..2
(1055 2120);
PAINT RED (1055 2120);
FORCEPROP 2 LAST CDS_LIB mstr_misc
J 0
(1055 2120);
PAINT ORANGE (1055 2120);
DISPLAY INVISIBLE (1055 2120);
FORCEPROP 1 LAST COMMENT_BODY TRUE
R 1
J 0
(1130 1895);
DISPLAY 0.872340 (1130 1895);
PAINT GREEN (1130 1895);
DISPLAY INVISIBLE (1130 1895);
FORCEADD DNS..2
(1055 1795);
PAINT RED (1055 1795);
FORCEPROP 2 LAST CDS_LIB mstr_misc
J 0
(1055 1795);
PAINT ORANGE (1055 1795);
DISPLAY INVISIBLE (1055 1795);
FORCEPROP 1 LAST COMMENT_BODY TRUE
R 1
J 0
(1130 1570);
DISPLAY 0.872340 (1130 1570);
PAINT GREEN (1130 1570);
DISPLAY INVISIBLE (1130 1570);
FORCEADD DNS..2
(1055 1470);
PAINT RED (1055 1470);
FORCEPROP 2 LAST CDS_LIB mstr_misc
J 0
(1055 1470);
PAINT ORANGE (1055 1470);
DISPLAY INVISIBLE (1055 1470);
FORCEPROP 1 LAST COMMENT_BODY TRUE
R 1
J 0
(1130 1245);
DISPLAY 0.872340 (1130 1245);
PAINT GREEN (1130 1245);
DISPLAY INVISIBLE (1130 1245);
FORCEADD DNS..2
(-3295 4420);
PAINT RED (-3295 4420);
FORCEPROP 2 LAST CDS_LIB mstr_misc
J 0
(-3295 4420);
PAINT ORANGE (-3295 4420);
DISPLAY INVISIBLE (-3295 4420);
FORCEPROP 1 LAST COMMENT_BODY TRUE
R 1
J 0
(-3220 4195);
DISPLAY 0.872340 (-3220 4195);
PAINT GREEN (-3220 4195);
DISPLAY INVISIBLE (-3220 4195);
FORCEADD DNS..2
(1055 1145);
PAINT RED (1055 1145);
FORCEPROP 2 LAST CDS_LIB mstr_misc
J 0
(1055 1145);
PAINT ORANGE (1055 1145);
DISPLAY INVISIBLE (1055 1145);
FORCEPROP 1 LAST COMMENT_BODY TRUE
R 1
J 0
(1130 920);
DISPLAY 0.872340 (1130 920);
PAINT GREEN (1130 920);
DISPLAY INVISIBLE (1130 920);
FORCEADD DNS..2
(-3320 1145);
PAINT RED (-3320 1145);
FORCEPROP 2 LAST CDS_LIB mstr_misc
J 0
(-3320 1145);
PAINT ORANGE (-3320 1145);
DISPLAY INVISIBLE (-3320 1145);
FORCEPROP 1 LAST COMMENT_BODY TRUE
R 1
J 0
(-3245 920);
DISPLAY 0.872340 (-3245 920);
PAINT GREEN (-3245 920);
DISPLAY INVISIBLE (-3245 920);
FORCEADD DNS..2
(1055 4395);
PAINT RED (1055 4395);
FORCEPROP 2 LAST CDS_LIB mstr_misc
J 0
(1055 4395);
PAINT ORANGE (1055 4395);
DISPLAY INVISIBLE (1055 4395);
FORCEPROP 1 LAST COMMENT_BODY TRUE
R 1
J 0
(1130 4170);
DISPLAY 0.872340 (1130 4170);
PAINT GREEN (1130 4170);
DISPLAY INVISIBLE (1130 4170);
FORCEADD DNS..2
(1055 2445);
PAINT RED (1055 2445);
FORCEPROP 2 LAST CDS_LIB mstr_misc
J 0
(1055 2445);
PAINT ORANGE (1055 2445);
DISPLAY INVISIBLE (1055 2445);
FORCEPROP 1 LAST COMMENT_BODY TRUE
R 1
J 0
(1130 2220);
DISPLAY 0.872340 (1130 2220);
PAINT GREEN (1130 2220);
DISPLAY INVISIBLE (1130 2220);
FORCEADD INTEL_CORP_BPAGE..1
(2650 500);
FORCEPROP 1 LAST CDS_CON_LAST_MODIFIED Fri Jun 16 17:48:41 2017
J 0
(1225 825);
PAINT ORANGE (1225 825);
DISPLAY INVISIBLE (1225 825);
FORCEPROP 1 LAST CUSTOM_TXT_CDS <CURRENT_DESIGN_SHEET> OF <TOTAL_DESIGN_SHEETS>
J 0
(2150 525);
PAINT ORANGE (2150 525);
FORCEPROP 1 LAST CUSTOM_TXT_CDS <CON_LAST_MODIFIED>
J 0
(-1350 600);
PAINT ORANGE (-1350 600);
FORCEPROP 2 LAST CUSTOM_TXT_CDS <XR_PAGE_TITLE>
J 0
(-5240 5750);
DISPLAY 0.638298 (-5240 5750);
PAINT PINK (-5240 5750);
DISPLAY INVISIBLE (-5240 5750);
FORCEPROP 1 LAST SCH_TITLE DB1200ZL CLOCK TERMINATION
J 0
(-5300 550);
DISPLAY 1.212766 (-5300 550);
PAINT ORANGE (-5300 550);
FORCEPROP 2 LAST PAGE_BORDER TRUE
J 0
(-5240 5750);
DISPLAY 0.617021 (-5240 5750);
PAINT PINK (-5240 5750);
DISPLAY INVISIBLE (-5240 5750);
FORCEPROP 2 LAST CDS_LIB mstr_symbols
J 0
(2650 500);
PAINT MONO (2650 500);
DISPLAY INVISIBLE (2650 500);
FORCEPROP 1 LAST COMMENT_BODY TRUE
J 0
(2662 512);
DISPLAY 0.468085 (2662 512);
PAINT GREEN (2662 512);
DISPLAY INVISIBLE (2662 512);
FORCEPROP 2 LAST CDS_XR_PAGE_TITLE CR-103 : @BASEBOARD_FAB2_LIB.BASEBOARD_FAB2(SCH_1):PAGE103
J 0
(-5240 5750);
DISPLAY 0.638298 (-5240 5750);
PAINT PINK (-5240 5750);
DISPLAY INVISIBLE (-5240 5750);
FORCEADD DNS..2
(-3320 1470);
PAINT RED (-3320 1470);
FORCEPROP 2 LAST CDS_LIB mstr_misc
J 0
(-3320 1470);
PAINT ORANGE (-3320 1470);
DISPLAY INVISIBLE (-3320 1470);
FORCEPROP 1 LAST COMMENT_BODY TRUE
R 1
J 0
(-3245 1245);
DISPLAY 0.872340 (-3245 1245);
PAINT GREEN (-3245 1245);
DISPLAY INVISIBLE (-3245 1245);
WIRE 16 -1 (-2800 4075)(-2800 4025);
WIRE 16 -1 (-3225 4075)(-2800 4075);
WIRE 16 -1 (-2800 3750)(-2800 3700);
WIRE 16 -1 (-3225 3750)(-2800 3750);
WIRE 16 -1 (-2800 3425)(-2800 3375);
WIRE 16 -1 (-3225 3425)(-2800 3425);
WIRE 16 -1 (-2800 3100)(-2800 3050);
WIRE 16 -1 (-3225 3100)(-2800 3100);
WIRE 16 -1 (-2800 2775)(-2800 2725);
WIRE 16 -1 (-3225 2775)(-2800 2775);
WIRE 16 -1 (-2800 2450)(-2800 2400);
WIRE 16 -1 (-3225 2450)(-2800 2450);
WIRE 16 -1 (-2800 2125)(-2800 2075);
WIRE 16 -1 (-3225 2125)(-2800 2125);
WIRE 16 -1 (-2800 1800)(-2800 1750);
WIRE 16 -1 (-3225 1800)(-2800 1800);
WIRE 16 -1 (-2800 1475)(-2800 1425);
WIRE 16 -1 (-3225 1475)(-2800 1475);
WIRE 16 -1 (-2800 1150)(-2800 1100);
WIRE 16 -1 (-3225 1150)(-2800 1150);
WIRE 16 -1 (1550 4725)(1550 4675);
WIRE 16 -1 (1125 4725)(1550 4725);
WIRE 16 -1 (1575 4400)(1575 4350);
WIRE 16 -1 (1150 4400)(1575 4400);
WIRE 16 -1 (1550 4075)(1550 4025);
WIRE 16 -1 (1125 4075)(1550 4075);
WIRE 16 -1 (1575 3750)(1575 3700);
WIRE 16 -1 (1150 3750)(1575 3750);
WIRE 16 -1 (1575 3425)(1575 3375);
WIRE 16 -1 (1150 3425)(1575 3425);
WIRE 16 -1 (1600 3100)(1600 3050);
WIRE 16 -1 (1175 3100)(1600 3100);
WIRE 16 -1 (1575 2775)(1575 2725);
WIRE 16 -1 (1150 2775)(1575 2775);
WIRE 16 -1 (1575 2450)(1575 2400);
WIRE 16 -1 (1150 2450)(1575 2450);
WIRE 16 -1 (1575 2125)(1575 2075);
WIRE 16 -1 (1150 2125)(1575 2125);
WIRE 16 -1 (1575 1800)(1575 1750);
WIRE 16 -1 (1150 1800)(1575 1800);
WIRE 16 -1 (1575 1475)(1575 1425);
WIRE 16 -1 (1150 1475)(1575 1475);
WIRE 16 -1 (1575 1150)(1575 1100);
WIRE 16 -1 (1150 1150)(1575 1150);
WIRE 16 -1 (-2775 4425)(-2775 4375);
WIRE 16 -1 (-3200 4425)(-2775 4425);
WIRE 16 -1 (-2800 4800)(-2800 4750);
WIRE 16 -1 (-3225 4800)(-2800 4800);
WIRE 16 -1 (950 2125)(800 2125);
WIRE 16 -1 (800 2225)(400 2225);
WIRE 16 -1 (800 2125)(800 2225);
WIRE 16 -1 (1900 2225)(800 2225);
FORCEPROP 2 LAST SIG_NAME CLK_100M_CPU0_BCLK1_DP
J 0
(1275 2235);
DISPLAY 0.617021 (1275 2235);
PAINT ORANGE (1275 2235);
WIRE 16 -1 (200 3850)(-625 3850);
FORCEPROP 2 LAST SIG_NAME CLK_100M_CPU0_RC_REFCLK0_R_DN
J 0
(-610 3860);
DISPLAY 0.617021 (-610 3860);
PAINT ORANGE (-610 3860);
WIRE 16 -1 (-3425 3425)(-3575 3425);
WIRE 16 -1 (-3825 3525)(-3575 3525);
WIRE 16 -1 (-3575 3425)(-3575 3525);
WIRE 16 -1 (-3575 3525)(-2275 3525);
FORCEPROP 2 LAST SIG_NAME CLK_100M_CPU1_PE_REFCLK_DP
J 0
(-2950 3535);
DISPLAY 0.617021 (-2950 3535);
PAINT ORANGE (-2950 3535);
WIRE 16 -1 (-3425 4075)(-3575 4075);
WIRE 16 -1 (-3575 4075)(-3575 4175);
WIRE 16 -1 (-3825 4175)(-3575 4175);
WIRE 16 -1 (-3575 4175)(-2275 4175);
FORCEPROP 2 LAST SIG_NAME CLK_100M_CPU1_RC_REFCLK0_DP
J 0
(-2950 4185);
DISPLAY 0.617021 (-2950 4185);
PAINT ORANGE (-2950 4185);
WIRE 16 -1 (950 4400)(800 4400);
WIRE 16 -1 (800 4500)(400 4500);
WIRE 16 -1 (800 4400)(800 4500);
WIRE 16 -1 (1900 4500)(800 4500);
FORCEPROP 2 LAST SIG_NAME CLK_100M_CPU0_RC_REFCLK1_DN
J 0
(1275 4510);
DISPLAY 0.617021 (1275 4510);
PAINT ORANGE (1275 4510);
WIRE 16 -1 (200 4500)(-625 4500);
FORCEPROP 2 LAST SIG_NAME CLK_100M_CPU0_RC_REFCLK1_R_DN
J 0
(-585 4510);
DISPLAY 0.617021 (-585 4510);
PAINT ORANGE (-585 4510);
WIRE 16 -1 (-3425 4800)(-3575 4800);
WIRE 16 -1 (-3825 4900)(-3575 4900);
FORCEPROP 0 LAST SIG_NAME CLK_100M_CPU1_RC_REFCLK1_DP
J 0
(-2950 4910);
DISPLAY 0.617021 (-2950 4910);
PAINT ORANGE (-2950 4910);
WIRE 16 -1 (-3575 4800)(-3575 4900);
WIRE 16 -1 (-3575 4900)(-2275 4900);
WIRE 16 -1 (-4025 4175)(-4850 4175);
FORCEPROP 2 LAST SIG_NAME CLK_100M_CPU1_RC_REFCLK0_R_DP
J 0
(-4810 4185);
DISPLAY 0.617021 (-4810 4185);
PAINT ORANGE (-4810 4185);
WIRE 16 -1 (925 4075)(775 4075);
WIRE 16 -1 (775 4075)(775 4175);
WIRE 16 -1 (775 4175)(400 4175);
WIRE 16 -1 (1900 4175)(775 4175);
FORCEPROP 2 LAST SIG_NAME CLK_100M_CPU0_RC_REFCLK0_DP
J 0
(1275 4185);
DISPLAY 0.617021 (1275 4185);
PAINT ORANGE (1275 4185);
WIRE 16 -1 (925 4725)(775 4725);
WIRE 16 -1 (775 4825)(400 4825);
WIRE 16 -1 (775 4725)(775 4825);
WIRE 16 -1 (1900 4825)(775 4825);
FORCEPROP 2 LAST SIG_NAME CLK_100M_CPU0_RC_REFCLK1_DP
J 0
(1275 4835);
DISPLAY 0.617021 (1275 4835);
PAINT ORANGE (1275 4835);
WIRE 16 -1 (950 2450)(800 2450);
WIRE 16 -1 (800 2550)(400 2550);
WIRE 16 -1 (800 2450)(800 2550);
WIRE 16 -1 (1900 2550)(800 2550);
FORCEPROP 2 LAST SIG_NAME CLK_100M_CPU0_BCLK2_DN
J 0
(1275 2560);
DISPLAY 0.617021 (1275 2560);
PAINT ORANGE (1275 2560);
WIRE 16 -1 (950 2775)(800 2775);
WIRE 16 -1 (800 2875)(400 2875);
WIRE 16 -1 (800 2775)(800 2875);
WIRE 16 -1 (1900 2875)(800 2875);
FORCEPROP 2 LAST SIG_NAME CLK_100M_CPU0_BCLK2_DP
J 0
(1275 2885);
DISPLAY 0.617021 (1275 2885);
PAINT ORANGE (1275 2885);
WIRE 16 -1 (975 3100)(825 3100);
WIRE 16 -1 (825 3200)(400 3200);
WIRE 16 -1 (825 3100)(825 3200);
WIRE 16 -1 (1900 3200)(825 3200);
FORCEPROP 2 LAST SIG_NAME CLK_100M_CPU0_PE_REFCLK_DN
J 0
(1275 3210);
DISPLAY 0.617021 (1275 3210);
PAINT ORANGE (1275 3210);
WIRE 16 -1 (950 3425)(800 3425);
WIRE 16 -1 (800 3525)(400 3525);
WIRE 16 -1 (800 3425)(800 3525);
WIRE 16 -1 (1900 3525)(800 3525);
FORCEPROP 2 LAST SIG_NAME CLK_100M_CPU0_PE_REFCLK_DP
J 0
(1275 3535);
DISPLAY 0.617021 (1275 3535);
PAINT ORANGE (1275 3535);
WIRE 16 -1 (950 3750)(800 3750);
WIRE 16 -1 (800 3850)(400 3850);
WIRE 16 -1 (800 3750)(800 3850);
WIRE 16 -1 (1900 3850)(800 3850);
FORCEPROP 2 LAST SIG_NAME CLK_100M_CPU0_RC_REFCLK0_DN
J 0
(1275 3860);
DISPLAY 0.617021 (1275 3860);
PAINT ORANGE (1275 3860);
WIRE 16 -1 (950 1150)(800 1150);
WIRE 16 -1 (400 1250)(800 1250);
WIRE 16 -1 (800 1150)(800 1250);
WIRE 16 -1 (800 1250)(1900 1250);
FORCEPROP 2 LAST SIG_NAME CLK_100M_CPU0_BCLK0_DN
J 0
(1275 1260);
DISPLAY 0.617021 (1275 1260);
PAINT ORANGE (1275 1260);
WIRE 16 -1 (950 1475)(800 1475);
WIRE 16 -1 (400 1575)(800 1575);
WIRE 16 -1 (800 1475)(800 1575);
WIRE 16 -1 (800 1575)(1900 1575);
FORCEPROP 2 LAST SIG_NAME CLK_100M_CPU0_BCLK0_DP
J 0
(1275 1585);
DISPLAY 0.617021 (1275 1585);
PAINT ORANGE (1275 1585);
WIRE 16 -1 (950 1800)(800 1800);
WIRE 16 -1 (400 1900)(800 1900);
WIRE 16 -1 (800 1800)(800 1900);
WIRE 16 -1 (800 1900)(1900 1900);
FORCEPROP 2 LAST SIG_NAME CLK_100M_CPU0_BCLK1_DN
J 0
(1275 1910);
DISPLAY 0.617021 (1275 1910);
PAINT ORANGE (1275 1910);
WIRE 16 -1 (200 3200)(-625 3200);
FORCEPROP 2 LAST SIG_NAME CLK_100M_CPU0_PE_REFCLK_R_DN
J 0
(-610 3210);
DISPLAY 0.617021 (-610 3210);
PAINT ORANGE (-610 3210);
WIRE 16 -1 (200 2875)(-625 2875);
FORCEPROP 2 LAST SIG_NAME CLK_100M_CPU0_BCLK2_R_DP
J 0
(-585 2885);
DISPLAY 0.617021 (-585 2885);
PAINT ORANGE (-585 2885);
WIRE 16 -1 (200 2550)(-625 2550);
FORCEPROP 2 LAST SIG_NAME CLK_100M_CPU0_BCLK2_R_DN
J 0
(-585 2560);
DISPLAY 0.617021 (-585 2560);
PAINT ORANGE (-585 2560);
WIRE 16 -1 (200 2225)(-625 2225);
FORCEPROP 2 LAST SIG_NAME CLK_100M_CPU0_BCLK1_R_DP
J 0
(-585 2235);
DISPLAY 0.617021 (-585 2235);
PAINT ORANGE (-585 2235);
WIRE 16 -1 (200 1900)(-625 1900);
FORCEPROP 2 LAST SIG_NAME CLK_100M_CPU0_BCLK1_R_DN
J 0
(-585 1910);
DISPLAY 0.617021 (-585 1910);
PAINT ORANGE (-585 1910);
WIRE 16 -1 (200 1250)(-625 1250);
FORCEPROP 2 LAST SIG_NAME CLK_100M_CPU0_BCLK0_R_DN
J 0
(-585 1260);
DISPLAY 0.617021 (-585 1260);
PAINT ORANGE (-585 1260);
WIRE 16 -1 (200 1575)(-625 1575);
FORCEPROP 2 LAST SIG_NAME CLK_100M_CPU0_BCLK0_R_DP
J 0
(-585 1585);
DISPLAY 0.617021 (-585 1585);
PAINT ORANGE (-585 1585);
WIRE 16 -1 (200 4825)(-625 4825);
FORCEPROP 2 LAST SIG_NAME CLK_100M_CPU0_RC_REFCLK1_R_DP
J 0
(-610 4835);
DISPLAY 0.617021 (-610 4835);
PAINT ORANGE (-610 4835);
WIRE 16 -1 (200 4175)(-625 4175);
FORCEPROP 2 LAST SIG_NAME CLK_100M_CPU0_RC_REFCLK0_R_DP
J 0
(-610 4185);
DISPLAY 0.617021 (-610 4185);
PAINT ORANGE (-610 4185);
WIRE 16 -1 (200 3525)(-625 3525);
FORCEPROP 2 LAST SIG_NAME CLK_100M_CPU0_PE_REFCLK_R_DP
J 0
(-610 3535);
DISPLAY 0.617021 (-610 3535);
PAINT ORANGE (-610 3535);
WIRE 16 -1 (-3400 4425)(-3550 4425);
WIRE 16 -1 (-3825 4525)(-3550 4525);
FORCEPROP 0 LAST SIG_NAME CLK_100M_CPU1_RC_REFCLK1_DN
J 0
(-2950 4535);
DISPLAY 0.617021 (-2950 4535);
PAINT ORANGE (-2950 4535);
WIRE 16 -1 (-3550 4425)(-3550 4525);
WIRE 16 -1 (-3550 4525)(-2275 4525);
WIRE 16 -1 (-3425 2125)(-3575 2125);
WIRE 16 -1 (-3825 2225)(-3575 2225);
WIRE 16 -1 (-3575 2125)(-3575 2225);
WIRE 16 -1 (-3575 2225)(-2275 2225);
FORCEPROP 2 LAST SIG_NAME CLK_100M_CPU1_BCLK1_DP
J 0
(-2950 2235);
DISPLAY 0.617021 (-2950 2235);
PAINT ORANGE (-2950 2235);
WIRE 16 -1 (-3425 2450)(-3575 2450);
WIRE 16 -1 (-3825 2550)(-3575 2550);
WIRE 16 -1 (-3575 2450)(-3575 2550);
WIRE 16 -1 (-3575 2550)(-2275 2550);
FORCEPROP 2 LAST SIG_NAME CLK_100M_CPU1_BCLK2_DN
J 0
(-2950 2560);
DISPLAY 0.617021 (-2950 2560);
PAINT ORANGE (-2950 2560);
WIRE 16 -1 (-3425 2775)(-3575 2775);
WIRE 16 -1 (-3825 2875)(-3575 2875);
WIRE 16 -1 (-3575 2775)(-3575 2875);
WIRE 16 -1 (-3575 2875)(-2275 2875);
FORCEPROP 2 LAST SIG_NAME CLK_100M_CPU1_BCLK2_DP
J 0
(-2950 2885);
DISPLAY 0.617021 (-2950 2885);
PAINT ORANGE (-2950 2885);
WIRE 16 -1 (-3425 3100)(-3575 3100);
WIRE 16 -1 (-3825 3200)(-3575 3200);
WIRE 16 -1 (-3575 3100)(-3575 3200);
WIRE 16 -1 (-3575 3200)(-2275 3200);
FORCEPROP 2 LAST SIG_NAME CLK_100M_CPU1_PE_REFCLK_DN
J 0
(-2950 3210);
DISPLAY 0.617021 (-2950 3210);
PAINT ORANGE (-2950 3210);
WIRE 16 -1 (-3425 3750)(-3575 3750);
WIRE 16 -1 (-3825 3850)(-3575 3850);
WIRE 16 -1 (-3575 3750)(-3575 3850);
WIRE 16 -1 (-3575 3850)(-2275 3850);
FORCEPROP 2 LAST SIG_NAME CLK_100M_CPU1_RC_REFCLK0_DN
J 0
(-2950 3860);
DISPLAY 0.617021 (-2950 3860);
PAINT ORANGE (-2950 3860);
WIRE 16 -1 (-3425 1150)(-3575 1150);
WIRE 16 -1 (-3825 1250)(-3575 1250);
WIRE 16 -1 (-3575 1150)(-3575 1250);
WIRE 16 -1 (-3575 1250)(-2275 1250);
FORCEPROP 2 LAST SIG_NAME CLK_100M_CPU1_BCLK0_DN
J 0
(-2950 1260);
DISPLAY 0.617021 (-2950 1260);
PAINT ORANGE (-2950 1260);
WIRE 16 -1 (-3425 1475)(-3575 1475);
WIRE 16 -1 (-3825 1575)(-3575 1575);
WIRE 16 -1 (-3575 1475)(-3575 1575);
WIRE 16 -1 (-3575 1575)(-2275 1575);
FORCEPROP 2 LAST SIG_NAME CLK_100M_CPU1_BCLK0_DP
J 0
(-2950 1585);
DISPLAY 0.617021 (-2950 1585);
PAINT ORANGE (-2950 1585);
WIRE 16 -1 (-3425 1800)(-3575 1800);
WIRE 16 -1 (-3825 1900)(-3575 1900);
WIRE 16 -1 (-3575 1800)(-3575 1900);
WIRE 16 -1 (-3575 1900)(-2275 1900);
FORCEPROP 2 LAST SIG_NAME CLK_100M_CPU1_BCLK1_DN
J 0
(-2950 1910);
DISPLAY 0.617021 (-2950 1910);
PAINT ORANGE (-2950 1910);
WIRE 16 -1 (-4025 4900)(-4850 4900);
FORCEPROP 0 LAST SIG_NAME CLK_100M_CPU1_RC_REFCLK1_R_DP
J 0
(-4800 4910);
DISPLAY 0.617021 (-4800 4910);
PAINT ORANGE (-4800 4910);
WIRE 16 -1 (-4025 4525)(-4850 4525);
FORCEPROP 0 LAST SIG_NAME CLK_100M_CPU1_RC_REFCLK1_R_DN
J 0
(-4800 4535);
DISPLAY 0.617021 (-4800 4535);
PAINT ORANGE (-4800 4535);
WIRE 16 -1 (-4025 3850)(-4850 3850);
FORCEPROP 2 LAST SIG_NAME CLK_100M_CPU1_RC_REFCLK0_R_DN
J 0
(-4810 3860);
DISPLAY 0.617021 (-4810 3860);
PAINT ORANGE (-4810 3860);
WIRE 16 -1 (-4025 3525)(-4850 3525);
FORCEPROP 2 LAST SIG_NAME CLK_100M_CPU1_PE_REFCLK_R_DP
J 0
(-4810 3535);
DISPLAY 0.617021 (-4810 3535);
PAINT ORANGE (-4810 3535);
WIRE 16 -1 (-4025 3200)(-4850 3200);
FORCEPROP 0 LAST SIG_NAME CLK_100M_CPU1_PE_REFCLK_R_DN
J 0
(-4810 3210);
DISPLAY 0.617021 (-4810 3210);
PAINT ORANGE (-4810 3210);
WIRE 16 -1 (-4025 2875)(-4850 2875);
FORCEPROP 0 LAST SIG_NAME CLK_100M_CPU1_BCLK2_R_DP
J 0
(-4800 2885);
DISPLAY 0.617021 (-4800 2885);
PAINT ORANGE (-4800 2885);
WIRE 16 -1 (-4025 2550)(-4850 2550);
FORCEPROP 2 LAST SIG_NAME CLK_100M_CPU1_BCLK2_R_DN
J 0
(-4800 2560);
DISPLAY 0.617021 (-4800 2560);
PAINT ORANGE (-4800 2560);
WIRE 16 -1 (-4025 2225)(-4850 2225);
FORCEPROP 2 LAST SIG_NAME CLK_100M_CPU1_BCLK1_R_DP
J 0
(-4800 2235);
DISPLAY 0.617021 (-4800 2235);
PAINT ORANGE (-4800 2235);
WIRE 16 -1 (-4025 1900)(-4850 1900);
FORCEPROP 2 LAST SIG_NAME CLK_100M_CPU1_BCLK1_R_DN
J 0
(-4800 1910);
DISPLAY 0.617021 (-4800 1910);
PAINT ORANGE (-4800 1910);
WIRE 16 -1 (-4025 1575)(-4850 1575);
FORCEPROP 2 LAST SIG_NAME CLK_100M_CPU1_BCLK0_R_DP
J 0
(-4800 1585);
DISPLAY 0.617021 (-4800 1585);
PAINT ORANGE (-4800 1585);
WIRE 16 -1 (-4025 1250)(-4850 1250);
FORCEPROP 2 LAST SIG_NAME CLK_100M_CPU1_BCLK0_R_DN
J 0
(-4800 1260);
DISPLAY 0.617021 (-4800 1260);
PAINT ORANGE (-4800 1260);
DOT 1 (-3575 1900);
DOT 1 (-3575 1575);
DOT 1 (-3575 1250);
DOT 1 (-3575 2875);
DOT 1 (-3575 2550);
DOT 1 (-3575 2225);
DOT 1 (-3575 3850);
DOT 1 (-3575 3525);
DOT 1 (-3575 3200);
DOT 1 (-3575 4175);
DOT 1 (-3575 4900);
DOT 1 (-3550 4525);
DOT 1 (800 1250);
DOT 1 (800 1575);
DOT 1 (800 1900);
DOT 1 (800 2225);
DOT 1 (800 2550);
DOT 1 (800 2875);
DOT 1 (825 3200);
DOT 1 (800 3525);
DOT 1 (800 3850);
DOT 1 (775 4175);
DOT 1 (800 4500);
DOT 1 (775 4825);
FORCENOTE
ROOM=DB1200Z
(-5300 700) 0;
DISPLAY LEFT (-5300 700);
DISPLAY 1.021277 (-5300 700);
PAINT PURPLE (-5300 700);
FORCENOTE
BOM_COST=SYS_CLOCK
(-5300 650) 0;
DISPLAY LEFT (-5300 650);
DISPLAY 1.021277 (-5300 650);
PAINT PURPLE (-5300 650);
QUIT
